FILE_TYPE = MACRO_DRAWING;
SET COLOR_WIRE YELLOW;
SET COLOR_PROP ORANGE;
SET COLOR_DOT WHITE;
SET COLOR_ARC YELLOW;
SET COLOR_BODY GREEN;
SET COLOR_NOTE PURPLE;
SET PROP_DISPLAY VALUE;
SET PAGE_NUMBER P192;
FORCEADD OFFPAGE..1
(-5200 2575);
FORCEPROP 2 LAST $XR0 81 
J 0
(-5481 2575);
DISPLAY 0.638298 (-5481 2575);
PAINT MONO (-5481 2575);
FORCEPROP 2 LAST CDS_LIB standard
J 0
(-5200 2575);
DISPLAY INVISIBLE (-5200 2575);
FORCEPROP 1 LAST OFFPAGE TRUE
J 0
(-4875 2450);
DISPLAY 0.872340 (-4875 2450);
PAINT GREEN (-4875 2450);
DISPLAY INVISIBLE (-4875 2450);
FORCEPROP 1 LAST COMMENT_BODY TRUE
J 0
(-5075 2475);
DISPLAY 0.872340 (-5075 2475);
PAINT GREEN (-5075 2475);
DISPLAY INVISIBLE (-5075 2475);
FORCEPROP 2 LAST PATH I1
J 0
(-5475 2625);
DISPLAY 0.680851 (-5475 2625);
DISPLAY INVISIBLE (-5475 2625);
FORCEADD VCC_CORE..1
(-3725 1925);
FORCEPROP 3 LASTPIN (-3725 1875) SIG_NAME P5V_AUX\g
J 0
(-3715 1885);
DISPLAY 0.659574 (-3715 1885);
PAINT MONO (-3715 1885);
DISPLAY INVISIBLE (-3715 1885);
FORCEPROP 1 LAST HDL_POWER P5V_AUX
J 1
(-3725 1975);
DISPLAY 0.489362 (-3725 1975);
PAINT GREEN (-3725 1975);
FORCEPROP 2 LAST CDS_LIB pure_quanta_power
J 0
(-3725 1925);
DISPLAY INVISIBLE (-3725 1925);
FORCEPROP 1 LAST PATH I10
J 0
(-3675 1950);
DISPLAY 0.872340 (-3675 1950);
PAINT AQUA (-3675 1950);
DISPLAY INVISIBLE (-3675 1950);
FORCEADD OFFPAGE..4
(1450 2025);
FORCEPROP 2 LAST $XR2 220 
J 0
(1876 2025);
DISPLAY 0.638298 (1876 2025);
PAINT MONO (1876 2025);
FORCEPROP 2 LAST $XR1 219 
J 0
(1756 2025);
DISPLAY 0.638298 (1756 2025);
PAINT MONO (1756 2025);
FORCEPROP 2 LAST $XR0 218 
J 0
(1636 2025);
DISPLAY 0.638298 (1636 2025);
PAINT MONO (1636 2025);
FORCEPROP 2 LAST CDS_LIB standard
J 0
(1450 2025);
DISPLAY INVISIBLE (1450 2025);
FORCEPROP 1 LAST OFFPAGE TRUE
J 0
(1775 1900);
DISPLAY 0.872340 (1775 1900);
PAINT GREEN (1775 1900);
DISPLAY INVISIBLE (1775 1900);
FORCEPROP 1 LAST COMMENT_BODY TRUE
J 0
(1425 1925);
DISPLAY 0.872340 (1425 1925);
PAINT GREEN (1425 1925);
DISPLAY INVISIBLE (1425 1925);
FORCEPROP 2 LAST PATH I100
J 0
(1900 2075);
DISPLAY 0.680851 (1900 2075);
DISPLAY INVISIBLE (1900 2075);
FORCEADD OFFPAGE..4
(1300 2825);
FORCEPROP 2 LAST $XR0 222 
J 0
(1486 2825);
DISPLAY 0.638298 (1486 2825);
PAINT MONO (1486 2825);
FORCEPROP 2 LAST CDS_LIB standard
J 0
(1300 2825);
DISPLAY INVISIBLE (1300 2825);
FORCEPROP 1 LAST OFFPAGE TRUE
J 0
(1625 2700);
DISPLAY 0.872340 (1625 2700);
PAINT GREEN (1625 2700);
DISPLAY INVISIBLE (1625 2700);
FORCEPROP 1 LAST COMMENT_BODY TRUE
J 0
(1275 2725);
DISPLAY 0.872340 (1275 2725);
PAINT GREEN (1275 2725);
DISPLAY INVISIBLE (1275 2725);
FORCEPROP 2 LAST PATH I101
J 0
(1500 2875);
DISPLAY 0.680851 (1500 2875);
DISPLAY INVISIBLE (1500 2875);
FORCEADD OFFPAGE..2
(1300 2925);
FORCEPROP 2 LAST $XR0 222 
J 0
(1489 2925);
DISPLAY 0.638298 (1489 2925);
PAINT MONO (1489 2925);
FORCEPROP 2 LAST CDS_LIB standard
J 0
(1300 2925);
DISPLAY INVISIBLE (1300 2925);
FORCEPROP 1 LAST OFFPAGE TRUE
J 0
(1625 2800);
DISPLAY 0.872340 (1625 2800);
PAINT GREEN (1625 2800);
DISPLAY INVISIBLE (1625 2800);
FORCEPROP 1 LAST COMMENT_BODY TRUE
J 0
(1255 2830);
DISPLAY 0.872340 (1255 2830);
PAINT GREEN (1255 2830);
DISPLAY INVISIBLE (1255 2830);
FORCEPROP 2 LAST PATH I102
J 0
(1500 2975);
DISPLAY 0.680851 (1500 2975);
DISPLAY INVISIBLE (1500 2975);
FORCEADD OFFPAGE..4
(1450 2625);
FORCEPROP 2 LAST $XR1 223 
J 0
(1756 2625);
DISPLAY 0.638298 (1756 2625);
PAINT MONO (1756 2625);
FORCEPROP 2 LAST $XR0 222 
J 0
(1636 2625);
DISPLAY 0.638298 (1636 2625);
PAINT MONO (1636 2625);
FORCEPROP 2 LAST CDS_LIB standard
J 0
(1450 2625);
DISPLAY INVISIBLE (1450 2625);
FORCEPROP 1 LAST OFFPAGE TRUE
J 0
(1775 2500);
DISPLAY 0.872340 (1775 2500);
PAINT GREEN (1775 2500);
DISPLAY INVISIBLE (1775 2500);
FORCEPROP 1 LAST COMMENT_BODY TRUE
J 0
(1425 2525);
DISPLAY 0.872340 (1425 2525);
PAINT GREEN (1425 2525);
DISPLAY INVISIBLE (1425 2525);
FORCEPROP 2 LAST PATH I103
J 0
(1775 2675);
DISPLAY 0.680851 (1775 2675);
DISPLAY INVISIBLE (1775 2675);
FORCEADD OFFPAGE..4
(1300 3125);
FORCEPROP 2 LAST $XR0 222 
J 0
(1486 3125);
DISPLAY 0.638298 (1486 3125);
PAINT MONO (1486 3125);
FORCEPROP 2 LAST CDS_LIB standard
J 0
(1300 3125);
DISPLAY INVISIBLE (1300 3125);
FORCEPROP 1 LAST OFFPAGE TRUE
J 0
(1625 3000);
DISPLAY 0.872340 (1625 3000);
PAINT GREEN (1625 3000);
DISPLAY INVISIBLE (1625 3000);
FORCEPROP 1 LAST COMMENT_BODY TRUE
J 0
(1275 3025);
DISPLAY 0.872340 (1275 3025);
PAINT GREEN (1275 3025);
DISPLAY INVISIBLE (1275 3025);
FORCEPROP 2 LAST PATH I104
J 0
(1500 3175);
DISPLAY 0.680851 (1500 3175);
DISPLAY INVISIBLE (1500 3175);
FORCEADD OFFPAGE..2
(1300 3225);
FORCEPROP 2 LAST $XR0 222 
J 0
(1489 3225);
DISPLAY 0.638298 (1489 3225);
PAINT MONO (1489 3225);
FORCEPROP 2 LAST CDS_LIB standard
J 0
(1300 3225);
DISPLAY INVISIBLE (1300 3225);
FORCEPROP 1 LAST OFFPAGE TRUE
J 0
(1625 3100);
DISPLAY 0.872340 (1625 3100);
PAINT GREEN (1625 3100);
DISPLAY INVISIBLE (1625 3100);
FORCEPROP 1 LAST COMMENT_BODY TRUE
J 0
(1255 3130);
DISPLAY 0.872340 (1255 3130);
PAINT GREEN (1255 3130);
DISPLAY INVISIBLE (1255 3130);
FORCEPROP 2 LAST PATH I105
J 0
(1500 3275);
DISPLAY 0.680851 (1500 3275);
DISPLAY INVISIBLE (1500 3275);
FORCEADD OFFPAGE..4
(1300 3425);
FORCEPROP 2 LAST $XR0 223 
J 0
(1486 3425);
DISPLAY 0.638298 (1486 3425);
PAINT MONO (1486 3425);
FORCEPROP 2 LAST CDS_LIB standard
J 0
(1300 3425);
DISPLAY INVISIBLE (1300 3425);
FORCEPROP 1 LAST OFFPAGE TRUE
J 0
(1625 3300);
DISPLAY 0.872340 (1625 3300);
PAINT GREEN (1625 3300);
DISPLAY INVISIBLE (1625 3300);
FORCEPROP 1 LAST COMMENT_BODY TRUE
J 0
(1275 3325);
DISPLAY 0.872340 (1275 3325);
PAINT GREEN (1275 3325);
DISPLAY INVISIBLE (1275 3325);
FORCEPROP 2 LAST PATH I106
J 0
(1500 3475);
DISPLAY 0.680851 (1500 3475);
DISPLAY INVISIBLE (1500 3475);
FORCEADD OFFPAGE..2
(1300 3525);
FORCEPROP 2 LAST $XR0 223 
J 0
(1489 3525);
DISPLAY 0.638298 (1489 3525);
PAINT MONO (1489 3525);
FORCEPROP 2 LAST CDS_LIB standard
J 0
(1300 3525);
DISPLAY INVISIBLE (1300 3525);
FORCEPROP 1 LAST OFFPAGE TRUE
J 0
(1625 3400);
DISPLAY 0.872340 (1625 3400);
PAINT GREEN (1625 3400);
DISPLAY INVISIBLE (1625 3400);
FORCEPROP 1 LAST COMMENT_BODY TRUE
J 0
(1255 3430);
DISPLAY 0.872340 (1255 3430);
PAINT GREEN (1255 3430);
DISPLAY INVISIBLE (1255 3430);
FORCEPROP 2 LAST PATH I107
J 0
(1500 3575);
DISPLAY 0.680851 (1500 3575);
DISPLAY INVISIBLE (1500 3575);
FORCEADD OFFPAGE..2
(1300 3825);
FORCEPROP 2 LAST $XR0 223 
J 0
(1489 3825);
DISPLAY 0.638298 (1489 3825);
PAINT MONO (1489 3825);
FORCEPROP 2 LAST CDS_LIB standard
J 0
(1300 3825);
DISPLAY INVISIBLE (1300 3825);
FORCEPROP 1 LAST OFFPAGE TRUE
J 0
(1625 3700);
DISPLAY 0.872340 (1625 3700);
PAINT GREEN (1625 3700);
DISPLAY INVISIBLE (1625 3700);
FORCEPROP 1 LAST COMMENT_BODY TRUE
J 0
(1255 3730);
DISPLAY 0.872340 (1255 3730);
PAINT GREEN (1255 3730);
DISPLAY INVISIBLE (1255 3730);
FORCEPROP 2 LAST PATH I108
J 0
(1500 3875);
DISPLAY 0.680851 (1500 3875);
DISPLAY INVISIBLE (1500 3875);
FORCEADD UNIVERSAL_GND..1
(1375 4250);
FORCEPROP 3 LASTPIN (1375 4300) SIG_NAME GND\g
J 0
(1385 4310);
DISPLAY 0.659574 (1385 4310);
PAINT MONO (1385 4310);
DISPLAY INVISIBLE (1385 4310);
FORCEPROP 2 LAST CDS_LIB pure_quanta_power
J 0
(1375 4250);
DISPLAY INVISIBLE (1375 4250);
FORCEPROP 1 LAST HDL_POWER GND
J 1
(1400 4175);
DISPLAY 0.872340 (1400 4175);
PAINT GREEN (1400 4175);
DISPLAY INVISIBLE (1400 4175);
FORCEPROP 1 LAST PATH I109
J 0
(1450 4250);
DISPLAY 0.872340 (1450 4250);
PAINT AQUA (1450 4250);
DISPLAY INVISIBLE (1450 4250);
FORCEADD VCC_CORE..1
(-3250 2225);
FORCEPROP 3 LASTPIN (-3250 2175) SIG_NAME P3V3_AUX\g
J 0
(-3240 2185);
DISPLAY 0.659574 (-3240 2185);
PAINT MONO (-3240 2185);
DISPLAY INVISIBLE (-3240 2185);
FORCEPROP 1 LAST HDL_POWER P3V3_AUX
J 1
(-3250 2275);
DISPLAY 0.489362 (-3250 2275);
PAINT GREEN (-3250 2275);
FORCEPROP 2 LAST CDS_LIB pure_quanta_power
J 0
(-3250 2225);
DISPLAY INVISIBLE (-3250 2225);
FORCEPROP 1 LAST PATH I11
J 0
(-3200 2250);
DISPLAY 0.872340 (-3200 2250);
PAINT AQUA (-3200 2250);
DISPLAY INVISIBLE (-3200 2250);
FORCEADD UNIVERSAL_GND..1
(1375 3950);
FORCEPROP 3 LASTPIN (1375 4000) SIG_NAME GND\g
J 0
(1385 4010);
DISPLAY 0.659574 (1385 4010);
PAINT MONO (1385 4010);
DISPLAY INVISIBLE (1385 4010);
FORCEPROP 2 LAST CDS_LIB pure_quanta_power
J 0
(1375 3950);
DISPLAY INVISIBLE (1375 3950);
FORCEPROP 1 LAST HDL_POWER GND
J 1
(1400 3875);
DISPLAY 0.872340 (1400 3875);
PAINT GREEN (1400 3875);
DISPLAY INVISIBLE (1400 3875);
FORCEPROP 1 LAST PATH I110
J 0
(1450 3950);
DISPLAY 0.872340 (1450 3950);
PAINT AQUA (1450 3950);
DISPLAY INVISIBLE (1450 3950);
FORCEADD OFFPAGE..4
(1275 4625);
FORCEPROP 2 LAST $XR0 220 
J 0
(1461 4625);
DISPLAY 0.638298 (1461 4625);
PAINT MONO (1461 4625);
FORCEPROP 2 LAST CDS_LIB standard
J 0
(1275 4625);
DISPLAY INVISIBLE (1275 4625);
FORCEPROP 1 LAST OFFPAGE TRUE
J 0
(1600 4500);
DISPLAY 0.872340 (1600 4500);
PAINT GREEN (1600 4500);
DISPLAY INVISIBLE (1600 4500);
FORCEPROP 1 LAST COMMENT_BODY TRUE
J 0
(1250 4525);
DISPLAY 0.872340 (1250 4525);
PAINT GREEN (1250 4525);
DISPLAY INVISIBLE (1250 4525);
FORCEPROP 2 LAST PATH I111
J 0
(1475 4675);
DISPLAY 0.680851 (1475 4675);
DISPLAY INVISIBLE (1475 4675);
FORCEADD OFFPAGE..2
(1300 4725);
FORCEPROP 2 LAST $XR0 220 
J 0
(1489 4725);
DISPLAY 0.638298 (1489 4725);
PAINT MONO (1489 4725);
FORCEPROP 2 LAST CDS_LIB standard
J 0
(1300 4725);
DISPLAY INVISIBLE (1300 4725);
FORCEPROP 1 LAST OFFPAGE TRUE
J 0
(1625 4600);
DISPLAY 0.872340 (1625 4600);
PAINT GREEN (1625 4600);
DISPLAY INVISIBLE (1625 4600);
FORCEPROP 1 LAST COMMENT_BODY TRUE
J 0
(1255 4630);
DISPLAY 0.872340 (1255 4630);
PAINT GREEN (1255 4630);
DISPLAY INVISIBLE (1255 4630);
FORCEPROP 2 LAST PATH I112
J 0
(1500 4775);
DISPLAY 0.680851 (1500 4775);
DISPLAY INVISIBLE (1500 4775);
FORCEADD OFFPAGE..4
(1300 4925);
FORCEPROP 2 LAST $XR0 220 
J 0
(1486 4925);
DISPLAY 0.638298 (1486 4925);
PAINT MONO (1486 4925);
FORCEPROP 2 LAST CDS_LIB standard
J 0
(1300 4925);
DISPLAY INVISIBLE (1300 4925);
FORCEPROP 1 LAST OFFPAGE TRUE
J 0
(1625 4800);
DISPLAY 0.872340 (1625 4800);
PAINT GREEN (1625 4800);
DISPLAY INVISIBLE (1625 4800);
FORCEPROP 1 LAST COMMENT_BODY TRUE
J 0
(1275 4825);
DISPLAY 0.872340 (1275 4825);
PAINT GREEN (1275 4825);
DISPLAY INVISIBLE (1275 4825);
FORCEPROP 2 LAST PATH I113
J 0
(1500 4975);
DISPLAY 0.680851 (1500 4975);
DISPLAY INVISIBLE (1500 4975);
FORCEADD OFFPAGE..2
(1300 5025);
FORCEPROP 2 LAST $XR0 220 
J 0
(1489 5025);
DISPLAY 0.638298 (1489 5025);
PAINT MONO (1489 5025);
FORCEPROP 2 LAST CDS_LIB standard
J 0
(1300 5025);
DISPLAY INVISIBLE (1300 5025);
FORCEPROP 1 LAST OFFPAGE TRUE
J 0
(1625 4900);
DISPLAY 0.872340 (1625 4900);
PAINT GREEN (1625 4900);
DISPLAY INVISIBLE (1625 4900);
FORCEPROP 1 LAST COMMENT_BODY TRUE
J 0
(1255 4930);
DISPLAY 0.872340 (1255 4930);
PAINT GREEN (1255 4930);
DISPLAY INVISIBLE (1255 4930);
FORCEPROP 2 LAST PATH I114
J 0
(1500 5075);
DISPLAY 0.680851 (1500 5075);
DISPLAY INVISIBLE (1500 5075);
FORCEADD OFFPAGE..4
(1300 5225);
FORCEPROP 2 LAST $XR0 219 
J 0
(1486 5225);
DISPLAY 0.638298 (1486 5225);
PAINT MONO (1486 5225);
FORCEPROP 2 LAST CDS_LIB standard
J 0
(1300 5225);
DISPLAY INVISIBLE (1300 5225);
FORCEPROP 1 LAST OFFPAGE TRUE
J 0
(1625 5100);
DISPLAY 0.872340 (1625 5100);
PAINT GREEN (1625 5100);
DISPLAY INVISIBLE (1625 5100);
FORCEPROP 1 LAST COMMENT_BODY TRUE
J 0
(1275 5125);
DISPLAY 0.872340 (1275 5125);
PAINT GREEN (1275 5125);
DISPLAY INVISIBLE (1275 5125);
FORCEPROP 2 LAST PATH I115
J 0
(1500 5275);
DISPLAY 0.680851 (1500 5275);
DISPLAY INVISIBLE (1500 5275);
FORCEADD OFFPAGE..2
(1300 5325);
FORCEPROP 2 LAST $XR0 219 
J 0
(1489 5325);
DISPLAY 0.638298 (1489 5325);
PAINT MONO (1489 5325);
FORCEPROP 2 LAST CDS_LIB standard
J 0
(1300 5325);
DISPLAY INVISIBLE (1300 5325);
FORCEPROP 1 LAST OFFPAGE TRUE
J 0
(1625 5200);
DISPLAY 0.872340 (1625 5200);
PAINT GREEN (1625 5200);
DISPLAY INVISIBLE (1625 5200);
FORCEPROP 1 LAST COMMENT_BODY TRUE
J 0
(1255 5230);
DISPLAY 0.872340 (1255 5230);
PAINT GREEN (1255 5230);
DISPLAY INVISIBLE (1255 5230);
FORCEPROP 2 LAST PATH I116
J 0
(1500 5375);
DISPLAY 0.680851 (1500 5375);
DISPLAY INVISIBLE (1500 5375);
FORCEADD OFFPAGE..4
(1300 5525);
FORCEPROP 2 LAST $XR0 219 
J 0
(1486 5525);
DISPLAY 0.638298 (1486 5525);
PAINT MONO (1486 5525);
FORCEPROP 2 LAST CDS_LIB standard
J 0
(1300 5525);
DISPLAY INVISIBLE (1300 5525);
FORCEPROP 1 LAST OFFPAGE TRUE
J 0
(1625 5400);
DISPLAY 0.872340 (1625 5400);
PAINT GREEN (1625 5400);
DISPLAY INVISIBLE (1625 5400);
FORCEPROP 1 LAST COMMENT_BODY TRUE
J 0
(1275 5425);
DISPLAY 0.872340 (1275 5425);
PAINT GREEN (1275 5425);
DISPLAY INVISIBLE (1275 5425);
FORCEPROP 2 LAST PATH I117
J 0
(1500 5575);
DISPLAY 0.680851 (1500 5575);
DISPLAY INVISIBLE (1500 5575);
FORCEADD OFFPAGE..2
(1300 5625);
FORCEPROP 2 LAST $XR0 219 
J 0
(1489 5625);
DISPLAY 0.638298 (1489 5625);
PAINT MONO (1489 5625);
FORCEPROP 2 LAST CDS_LIB standard
J 0
(1300 5625);
DISPLAY INVISIBLE (1300 5625);
FORCEPROP 1 LAST OFFPAGE TRUE
J 0
(1625 5500);
DISPLAY 0.872340 (1625 5500);
PAINT GREEN (1625 5500);
DISPLAY INVISIBLE (1625 5500);
FORCEPROP 1 LAST COMMENT_BODY TRUE
J 0
(1255 5530);
DISPLAY 0.872340 (1255 5530);
PAINT GREEN (1255 5530);
DISPLAY INVISIBLE (1255 5530);
FORCEPROP 2 LAST PATH I118
J 0
(1500 5675);
DISPLAY 0.680851 (1500 5675);
DISPLAY INVISIBLE (1500 5675);
FORCEADD OFFPAGE..4
(1325 5825);
FORCEPROP 2 LAST $XR0 218 
J 0
(1511 5825);
DISPLAY 0.638298 (1511 5825);
PAINT MONO (1511 5825);
FORCEPROP 2 LAST CDS_LIB standard
J 0
(1325 5825);
DISPLAY INVISIBLE (1325 5825);
FORCEPROP 1 LAST OFFPAGE TRUE
J 0
(1650 5700);
DISPLAY 0.872340 (1650 5700);
PAINT GREEN (1650 5700);
DISPLAY INVISIBLE (1650 5700);
FORCEPROP 1 LAST COMMENT_BODY TRUE
J 0
(1300 5725);
DISPLAY 0.872340 (1300 5725);
PAINT GREEN (1300 5725);
DISPLAY INVISIBLE (1300 5725);
FORCEPROP 2 LAST PATH I119
J 0
(1525 5875);
DISPLAY 0.680851 (1525 5875);
DISPLAY INVISIBLE (1525 5875);
FORCEADD Q_RES..2
(-3300 2525);
FORCEPROP 1 LAST LOCATION PR244
J 0
(-3250 2575);
DISPLAY 0.489362 (-3250 2575);
PAINT SKYBLUE (-3250 2575);
FORCEPROP 0 LAST $SEC 1
J 0
(-3275 2600);
DISPLAY 0.680851 (-3275 2600);
PAINT MONO (-3275 2600);
DISPLAY INVISIBLE (-3275 2600);
FORCEPROP 0 LAST CDS_SEC 1
J 0
(-3275 2600);
DISPLAY 1.021277 (-3275 2600);
DISPLAY INVISIBLE (-3275 2600);
FORCEPROP 1 LASTPIN (-3300 2625) $PN 1
J 0
(-3295 2587);
DISPLAY 0.489362 (-3295 2587);
PAINT MONO (-3295 2587);
FORCEPROP 1 LASTPIN (-3300 2425) $PN 2
J 0
(-3295 2435);
DISPLAY 0.489362 (-3295 2435);
PAINT MONO (-3295 2435);
FORCEPROP 1 LAST PACK_TYPE 0402LF
J 0
(-3250 2425);
DISPLAY 0.489362 (-3250 2425);
PAINT SKYBLUE (-3250 2425);
FORCEPROP 1 LAST WATTAGE 1/16W
J 0
(-3250 2500);
DISPLAY 0.489362 (-3250 2500);
PAINT SKYBLUE (-3250 2500);
FORCEPROP 1 LAST VALUE 9.53K
J 0
(-3250 2550);
DISPLAY 0.489362 (-3250 2550);
PAINT SKYBLUE (-3250 2550);
FORCEPROP 1 LAST TOLERANCE 1%
J 0
(-3250 2525);
DISPLAY 0.489362 (-3250 2525);
PAINT SKYBLUE (-3250 2525);
FORCEPROP 1 LAST MATERIAL CHIP
J 0
(-3250 2475);
DISPLAY 0.489362 (-3250 2475);
PAINT SKYBLUE (-3250 2475);
FORCEPROP 2 LAST CDS_LIB pure_quanta
J 0
(-3300 2525);
DISPLAY INVISIBLE (-3300 2525);
FORCEPROP 1 LAST PATH I12
J 0
(-3250 2700);
DISPLAY 0.978723 (-3250 2700);
PAINT WHITE (-3250 2700);
DISPLAY INVISIBLE (-3250 2700);
FORCEPROP 1 LAST PART_NUMBER CS29532FB06
J 0
(-3250 2450);
DISPLAY 0.489362 (-3250 2450);
PAINT SKYBLUE (-3250 2450);
DISPLAY INVISIBLE (-3250 2450);
FORCEADD OFFPAGE..2
(1325 5925);
FORCEPROP 2 LAST $XR0 218 
J 0
(1514 5925);
DISPLAY 0.638298 (1514 5925);
PAINT MONO (1514 5925);
FORCEPROP 2 LAST CDS_LIB standard
J 0
(1325 5925);
DISPLAY INVISIBLE (1325 5925);
FORCEPROP 1 LAST OFFPAGE TRUE
J 0
(1650 5800);
DISPLAY 0.872340 (1650 5800);
PAINT GREEN (1650 5800);
DISPLAY INVISIBLE (1650 5800);
FORCEPROP 1 LAST COMMENT_BODY TRUE
J 0
(1280 5830);
DISPLAY 0.872340 (1280 5830);
PAINT GREEN (1280 5830);
DISPLAY INVISIBLE (1280 5830);
FORCEPROP 2 LAST PATH I120
J 0
(1525 5975);
DISPLAY 0.680851 (1525 5975);
DISPLAY INVISIBLE (1525 5975);
FORCEADD OFFPAGE..4
(1300 6125);
FORCEPROP 2 LAST $XR0 218 
J 0
(1486 6125);
DISPLAY 0.638298 (1486 6125);
PAINT MONO (1486 6125);
FORCEPROP 2 LAST CDS_LIB standard
J 0
(1300 6125);
DISPLAY INVISIBLE (1300 6125);
FORCEPROP 1 LAST OFFPAGE TRUE
J 0
(1625 6000);
DISPLAY 0.872340 (1625 6000);
PAINT GREEN (1625 6000);
DISPLAY INVISIBLE (1625 6000);
FORCEPROP 1 LAST COMMENT_BODY TRUE
J 0
(1275 6025);
DISPLAY 0.872340 (1275 6025);
PAINT GREEN (1275 6025);
DISPLAY INVISIBLE (1275 6025);
FORCEPROP 2 LAST PATH I121
J 0
(1500 6175);
DISPLAY 0.680851 (1500 6175);
DISPLAY INVISIBLE (1500 6175);
FORCEADD OFFPAGE..2
(1300 6225);
FORCEPROP 2 LAST $XR0 218 
J 0
(1489 6225);
DISPLAY 0.638298 (1489 6225);
PAINT MONO (1489 6225);
FORCEPROP 2 LAST CDS_LIB standard
J 0
(1300 6225);
DISPLAY INVISIBLE (1300 6225);
FORCEPROP 1 LAST OFFPAGE TRUE
J 0
(1625 6100);
DISPLAY 0.872340 (1625 6100);
PAINT GREEN (1625 6100);
DISPLAY INVISIBLE (1625 6100);
FORCEPROP 1 LAST COMMENT_BODY TRUE
J 0
(1255 6130);
DISPLAY 0.872340 (1255 6130);
PAINT GREEN (1255 6130);
DISPLAY INVISIBLE (1255 6130);
FORCEPROP 2 LAST PATH I122
J 0
(1500 6275);
DISPLAY 0.680851 (1500 6275);
DISPLAY INVISIBLE (1500 6275);
FORCEADD OFFPAGE..2
(1525 6750);
FORCEPROP 2 LAST $XR4 223 
J 0
(2194 6750);
DISPLAY 0.638298 (2194 6750);
PAINT MONO (2194 6750);
FORCEPROP 2 LAST $XR3 222 
J 0
(2074 6750);
DISPLAY 0.638298 (2074 6750);
PAINT MONO (2074 6750);
FORCEPROP 2 LAST $XR2 220 
J 0
(1954 6750);
DISPLAY 0.638298 (1954 6750);
PAINT MONO (1954 6750);
FORCEPROP 2 LAST $XR1 219 
J 0
(1834 6750);
DISPLAY 0.638298 (1834 6750);
PAINT MONO (1834 6750);
FORCEPROP 2 LAST $XR0 218 
J 0
(1714 6750);
DISPLAY 0.638298 (1714 6750);
PAINT MONO (1714 6750);
FORCEPROP 2 LAST CDS_LIB standard
J 0
(1525 6750);
DISPLAY INVISIBLE (1525 6750);
FORCEPROP 1 LAST OFFPAGE TRUE
J 0
(1850 6625);
DISPLAY 0.872340 (1850 6625);
PAINT GREEN (1850 6625);
DISPLAY INVISIBLE (1850 6625);
FORCEPROP 1 LAST COMMENT_BODY TRUE
J 0
(1480 6655);
DISPLAY 0.872340 (1480 6655);
PAINT GREEN (1480 6655);
DISPLAY INVISIBLE (1480 6655);
FORCEPROP 2 LAST PATH I123
J 0
(2200 6800);
DISPLAY 0.680851 (2200 6800);
DISPLAY INVISIBLE (2200 6800);
FORCEADD Q_RES..1
(1300 7225);
FORCEPROP 1 LAST LOCATION PR253
J 0
(1075 7225);
DISPLAY 0.489362 (1075 7225);
PAINT SKYBLUE (1075 7225);
FORCEPROP 0 LAST $SEC 1
J 0
(1250 7325);
DISPLAY 0.680851 (1250 7325);
PAINT MONO (1250 7325);
DISPLAY INVISIBLE (1250 7325);
FORCEPROP 0 LAST CDS_SEC 1
J 0
(1250 7325);
DISPLAY 1.021277 (1250 7325);
DISPLAY INVISIBLE (1250 7325);
FORCEPROP 1 LASTPIN (1200 7225) $PN 1
J 0
(1212 7237);
DISPLAY 0.489362 (1212 7237);
PAINT MONO (1212 7237);
FORCEPROP 1 LASTPIN (1400 7225) $PN 2
J 0
(1362 7237);
DISPLAY 0.489362 (1362 7237);
PAINT MONO (1362 7237);
FORCEPROP 1 LAST WATTAGE 1/16W
J 2
(1750 7125);
DISPLAY 0.489362 (1750 7125);
PAINT SKYBLUE (1750 7125);
FORCEPROP 1 LAST MATERIAL CHIP
J 0
(1600 7250);
DISPLAY 0.489362 (1600 7250);
PAINT SKYBLUE (1600 7250);
FORCEPROP 1 LAST TOLERANCE 1%
J 0
(1500 7250);
DISPLAY 0.489362 (1500 7250);
PAINT SKYBLUE (1500 7250);
FORCEPROP 1 LAST VALUE 1
J 2
(1475 7250);
DISPLAY 0.489362 (1475 7250);
PAINT SKYBLUE (1475 7250);
FORCEPROP 1 LAST PACK_TYPE 0402LF
J 0
(1450 7125);
DISPLAY 0.489362 (1450 7125);
PAINT SKYBLUE (1450 7125);
FORCEPROP 2 LAST CDS_LIB pure_quanta
J 0
(1300 7225);
DISPLAY INVISIBLE (1300 7225);
FORCEPROP 1 LAST PATH I124
J 0
(1250 7375);
DISPLAY 0.978723 (1250 7375);
PAINT WHITE (1250 7375);
DISPLAY INVISIBLE (1250 7375);
FORCEPROP 1 LAST PART_NUMBER CS-1002FB04
J 0
(1450 7175);
DISPLAY 0.489362 (1450 7175);
PAINT SKYBLUE (1450 7175);
DISPLAY INVISIBLE (1450 7175);
FORCEADD VCC_CORE..1
(1825 7350);
FORCEPROP 3 LASTPIN (1825 7300) SIG_NAME P3V3_AUX\g
J 0
(1835 7310);
DISPLAY 0.659574 (1835 7310);
PAINT MONO (1835 7310);
DISPLAY INVISIBLE (1835 7310);
FORCEPROP 1 LAST HDL_POWER P3V3_AUX
J 1
(1825 7400);
DISPLAY 0.489362 (1825 7400);
PAINT GREEN (1825 7400);
FORCEPROP 2 LAST CDS_LIB pure_quanta_power
J 0
(1825 7350);
DISPLAY INVISIBLE (1825 7350);
FORCEPROP 1 LAST PATH I125
J 0
(1875 7375);
DISPLAY 0.872340 (1875 7375);
PAINT AQUA (1875 7375);
DISPLAY INVISIBLE (1875 7375);
FORCEADD OFFPAGE..4
(1300 3725);
FORCEPROP 2 LAST $XR0 223 
J 0
(1486 3725);
DISPLAY 0.638298 (1486 3725);
PAINT MONO (1486 3725);
FORCEPROP 2 LAST CDS_LIB standard
J 0
(1300 3725);
DISPLAY INVISIBLE (1300 3725);
FORCEPROP 1 LAST OFFPAGE TRUE
J 0
(1625 3600);
DISPLAY 0.872340 (1625 3600);
PAINT GREEN (1625 3600);
DISPLAY INVISIBLE (1625 3600);
FORCEPROP 1 LAST COMMENT_BODY TRUE
J 0
(1275 3625);
DISPLAY 0.872340 (1275 3625);
PAINT GREEN (1275 3625);
DISPLAY INVISIBLE (1275 3625);
FORCEPROP 2 LAST PATH I126
J 0
(1500 3775);
DISPLAY 0.680851 (1500 3775);
DISPLAY INVISIBLE (1500 3775);
FORCEADD Q_RES..1
(925 4025);
FORCEPROP 1 LAST LOCATION PR12
J 0
(875 4075);
DISPLAY 0.489362 (875 4075);
PAINT SKYBLUE (875 4075);
FORCEPROP 0 LAST $SEC 1
J 0
(875 4125);
DISPLAY 0.680851 (875 4125);
PAINT MONO (875 4125);
DISPLAY INVISIBLE (875 4125);
FORCEPROP 0 LAST CDS_SEC 1
J 0
(875 4125);
DISPLAY 1.021277 (875 4125);
DISPLAY INVISIBLE (875 4125);
FORCEPROP 1 LASTPIN (825 4025) $PN 1
J 0
(837 4037);
DISPLAY 0.489362 (837 4037);
PAINT MONO (837 4037);
FORCEPROP 1 LASTPIN (1025 4025) $PN 2
J 0
(987 4037);
DISPLAY 0.489362 (987 4037);
PAINT MONO (987 4037);
FORCEPROP 1 LAST PACK_TYPE 0402LF
J 0
(1025 3975);
DISPLAY 0.489362 (1025 3975);
PAINT SKYBLUE (1025 3975);
FORCEPROP 1 LAST TOLERANCE 5%
J 0
(950 3975);
DISPLAY 0.489362 (950 3975);
PAINT SKYBLUE (950 3975);
FORCEPROP 1 LAST VALUE 0
J 2
(925 3975);
DISPLAY 0.489362 (925 3975);
PAINT SKYBLUE (925 3975);
FORCEPROP 1 LAST WATTAGE 1/16W
J 2
(850 3975);
DISPLAY 0.489362 (850 3975);
PAINT SKYBLUE (850 3975);
FORCEPROP 1 LAST MATERIAL CHIP
J 0
(600 3975);
DISPLAY 0.489362 (600 3975);
PAINT SKYBLUE (600 3975);
FORCEPROP 2 LAST CDS_LIB pure_quanta
J 0
(925 4025);
DISPLAY INVISIBLE (925 4025);
FORCEPROP 1 LAST PATH I127
J 0
(875 4175);
DISPLAY 0.978723 (875 4175);
PAINT WHITE (875 4175);
DISPLAY INVISIBLE (875 4175);
FORCEPROP 1 LAST PART_NUMBER CS00002JB13
J 0
(250 3975);
DISPLAY 0.489362 (250 3975);
PAINT SKYBLUE (250 3975);
DISPLAY INVISIBLE (250 3975);
FORCEADD RAA229620GNPHA0..1
(-475 4475);
FORCEPROP 1 LAST LOCATION PU34
J 0
(-1025 7500);
DISPLAY 0.723404 (-1025 7500);
PAINT GREEN (-1025 7500);
FORCEPROP 2 LAST SEC 1
J 0
(-1025 7550);
DISPLAY 0.680851 (-1025 7550);
PAINT MONO (-1025 7550);
DISPLAY INVISIBLE (-1025 7550);
FORCEPROP 2 LASTPIN (175 2825) $PN 38
J 0
(185 2835);
DISPLAY 0.680851 (185 2835);
PAINT MONO (185 2835);
FORCEPROP 2 LASTPIN (175 3125) $PN 37
J 0
(185 3135);
DISPLAY 0.680851 (185 3135);
PAINT MONO (185 3135);
FORCEPROP 2 LASTPIN (175 3425) $PN 36
J 0
(185 3435);
DISPLAY 0.680851 (185 3435);
PAINT MONO (185 3435);
FORCEPROP 2 LASTPIN (175 3725) $PN 35
J 0
(185 3735);
DISPLAY 0.680851 (185 3735);
PAINT MONO (185 3735);
FORCEPROP 2 LASTPIN (175 4025) $PN 34
J 0
(185 4035);
DISPLAY 0.680851 (185 4035);
PAINT MONO (185 4035);
FORCEPROP 2 LASTPIN (175 4325) $PN 33
J 0
(185 4335);
DISPLAY 0.680851 (185 4335);
PAINT MONO (185 4335);
FORCEPROP 2 LASTPIN (175 4625) $PN 32
J 0
(185 4635);
DISPLAY 0.680851 (185 4635);
PAINT MONO (185 4635);
FORCEPROP 2 LASTPIN (175 4925) $PN 31
J 0
(185 4935);
DISPLAY 0.680851 (185 4935);
PAINT MONO (185 4935);
FORCEPROP 2 LASTPIN (175 5225) $PN 30
J 0
(185 5235);
DISPLAY 0.680851 (185 5235);
PAINT MONO (185 5235);
FORCEPROP 2 LASTPIN (175 5525) $PN 29
J 0
(185 5535);
DISPLAY 0.680851 (185 5535);
PAINT MONO (185 5535);
FORCEPROP 2 LASTPIN (175 5825) $PN 28
J 0
(185 5835);
DISPLAY 0.680851 (185 5835);
PAINT MONO (185 5835);
FORCEPROP 2 LASTPIN (175 6125) $PN 27
J 0
(185 6135);
DISPLAY 0.680851 (185 6135);
PAINT MONO (185 6135);
FORCEPROP 2 LASTPIN (-1175 7075) $PN 17
J 2
(-1185 7085);
DISPLAY 0.680851 (-1185 7085);
PAINT MONO (-1185 7085);
FORCEPROP 2 LASTPIN (-1175 2475) $PN 42
J 2
(-1185 2485);
DISPLAY 0.680851 (-1185 2485);
PAINT MONO (-1185 2485);
FORCEPROP 2 LASTPIN (-1175 5775) $PN 15
J 2
(-1185 5785);
DISPLAY 0.680851 (-1185 5785);
PAINT MONO (-1185 5785);
FORCEPROP 2 LASTPIN (-1175 3225) $PN 41
J 2
(-1185 3235);
DISPLAY 0.680851 (-1185 3235);
PAINT MONO (-1185 3235);
FORCEPROP 2 LASTPIN (-1175 7225) $PN 16
J 2
(-1185 7235);
DISPLAY 0.680851 (-1185 7235);
PAINT MONO (-1185 7235);
FORCEPROP 2 LASTPIN (-1175 1975) $PN 20
J 2
(-1185 1985);
DISPLAY 0.680851 (-1185 1985);
PAINT MONO (-1185 1985);
FORCEPROP 2 LASTPIN (-1175 6075) $PN 14
J 2
(-1185 6085);
DISPLAY 0.680851 (-1185 6085);
PAINT MONO (-1185 6085);
FORCEPROP 2 LASTPIN (-1175 5925) $PN 13
J 2
(-1185 5935);
DISPLAY 0.680851 (-1185 5935);
PAINT MONO (-1185 5935);
FORCEPROP 2 LASTPIN (175 2925) $PN 1
J 0
(185 2935);
DISPLAY 0.680851 (185 2935);
PAINT MONO (185 2935);
FORCEPROP 2 LASTPIN (175 3225) $PN 2
J 0
(185 3235);
DISPLAY 0.680851 (185 3235);
PAINT MONO (185 3235);
FORCEPROP 2 LASTPIN (175 3525) $PN 3
J 0
(185 3535);
DISPLAY 0.680851 (185 3535);
PAINT MONO (185 3535);
FORCEPROP 2 LASTPIN (175 3825) $PN 4
J 0
(185 3835);
DISPLAY 0.680851 (185 3835);
PAINT MONO (185 3835);
FORCEPROP 2 LASTPIN (175 4125) $PN 5
J 0
(185 4135);
DISPLAY 0.680851 (185 4135);
PAINT MONO (185 4135);
FORCEPROP 2 LASTPIN (175 4425) $PN 6
J 0
(185 4435);
DISPLAY 0.680851 (185 4435);
PAINT MONO (185 4435);
FORCEPROP 2 LASTPIN (175 4725) $PN 7
J 0
(185 4735);
DISPLAY 0.680851 (185 4735);
PAINT MONO (185 4735);
FORCEPROP 2 LASTPIN (175 5025) $PN 8
J 0
(185 5035);
DISPLAY 0.680851 (185 5035);
PAINT MONO (185 5035);
FORCEPROP 2 LASTPIN (175 5325) $PN 9
J 0
(185 5335);
DISPLAY 0.680851 (185 5335);
PAINT MONO (185 5335);
FORCEPROP 2 LASTPIN (175 5625) $PN 10
J 0
(185 5635);
DISPLAY 0.680851 (185 5635);
PAINT MONO (185 5635);
FORCEPROP 2 LASTPIN (175 5925) $PN 11
J 0
(185 5935);
DISPLAY 0.680851 (185 5935);
PAINT MONO (185 5935);
FORCEPROP 2 LASTPIN (175 6225) $PN 12
J 0
(185 6235);
DISPLAY 0.680851 (185 6235);
PAINT MONO (185 6235);
FORCEPROP 2 LASTPIN (-1175 3375) $PN 18
J 2
(-1185 3385);
DISPLAY 0.680851 (-1185 3385);
PAINT MONO (-1185 3385);
FORCEPROP 2 LASTPIN (-1175 4925) $PN 26
J 2
(-1185 4935);
DISPLAY 0.680851 (-1185 4935);
PAINT MONO (-1185 4935);
FORCEPROP 2 LASTPIN (-1175 3825) $PN 39
J 2
(-1185 3835);
DISPLAY 0.680851 (-1185 3835);
PAINT MONO (-1185 3835);
FORCEPROP 2 LASTPIN (-1175 6775) $PN 22
J 2
(-1185 6785);
DISPLAY 0.680851 (-1185 6785);
PAINT MONO (-1185 6785);
FORCEPROP 2 LASTPIN (-1175 6625) $PN 21
J 2
(-1185 6635);
DISPLAY 0.680851 (-1185 6635);
PAINT MONO (-1185 6635);
FORCEPROP 2 LASTPIN (-1175 6325) $PN 24
J 2
(-1185 6335);
DISPLAY 0.680851 (-1185 6335);
PAINT MONO (-1185 6335);
FORCEPROP 2 LASTPIN (-1175 6475) $PN 23
J 2
(-1185 6485);
DISPLAY 0.680851 (-1185 6485);
PAINT MONO (-1185 6485);
FORCEPROP 2 LASTPIN (175 2025) $PN 44
J 0
(185 2035);
DISPLAY 0.680851 (185 2035);
PAINT MONO (185 2035);
FORCEPROP 2 LASTPIN (175 2325) $PN 43
J 0
(185 2335);
DISPLAY 0.680851 (185 2335);
PAINT MONO (185 2335);
FORCEPROP 2 LASTPIN (-1175 1675) $PN TH
J 2
(-1185 1685);
DISPLAY 0.680851 (-1185 1685);
PAINT MONO (-1185 1685);
FORCEPROP 2 LASTPIN (175 7225) $PN 47
J 0
(185 7235);
DISPLAY 0.680851 (185 7235);
PAINT MONO (185 7235);
FORCEPROP 2 LASTPIN (175 6925) $PN 48
J 0
(185 6935);
DISPLAY 0.680851 (185 6935);
PAINT MONO (185 6935);
FORCEPROP 2 LASTPIN (-1175 2975) $PN 19
J 2
(-1185 2985);
DISPLAY 0.680851 (-1185 2985);
PAINT MONO (-1185 2985);
FORCEPROP 2 LASTPIN (-1175 1775) $PN 46
J 2
(-1185 1785);
DISPLAY 0.680851 (-1185 1785);
PAINT MONO (-1185 1785);
FORCEPROP 2 LASTPIN (-1175 1875) $PN 45
J 2
(-1185 1885);
DISPLAY 0.680851 (-1185 1885);
PAINT MONO (-1185 1885);
FORCEPROP 2 LASTPIN (-1175 5175) $PN 25
J 2
(-1185 5185);
DISPLAY 0.680851 (-1185 5185);
PAINT MONO (-1185 5185);
FORCEPROP 2 LASTPIN (-1175 4075) $PN 40
J 2
(-1185 4085);
DISPLAY 0.680851 (-1185 4085);
PAINT MONO (-1185 4085);
FORCEPROP 2 LAST PART_TYPE SMLF
J 0
(-625 7400);
DISPLAY 0.638298 (-625 7400);
FORCEPROP 1 LAST MATERIAL IC
J 0
(-1025 7350);
DISPLAY 0.723404 (-1025 7350);
PAINT GREEN (-1025 7350);
FORCEPROP 2 LAST VALUE RAA229620GNP#HA0
J 0
(-675 7350);
DISPLAY 0.489362 (-675 7350);
PAINT SKYBLUE (-675 7350);
FORCEPROP 2 LAST SEC_TYPE 
J 0
(-1025 7550);
DISPLAY 0.680851 (-1025 7550);
DISPLAY INVISIBLE (-1025 7550);
FORCEPROP 1 LAST NEEDS_NO_SIZE TRUE
J 0
(-475 4475);
DISPLAY 0.723404 (-475 4475);
PAINT GREEN (-475 4475);
DISPLAY INVISIBLE (-475 4475);
FORCEPROP 1 LAST CDS_LMAN_SYM_OUTLINE -550,2850,500,-2850
J 0
(-475 4475);
DISPLAY 0.468085 (-475 4475);
PAINT GREEN (-475 4475);
DISPLAY INVISIBLE (-475 4475);
FORCEPROP 2 LAST CDS_LIB pure_quanta
J 0
(-475 4475);
DISPLAY INVISIBLE (-475 4475);
FORCEPROP 1 LAST PATH I128
J 0
(-475 4475);
DISPLAY 0.723404 (-475 4475);
PAINT GREEN (-475 4475);
DISPLAY INVISIBLE (-475 4475);
FORCEPROP 1 LAST PART_NUMBER ARF0TGP4002
J 0
(-1025 7425);
DISPLAY 0.723404 (-1025 7425);
PAINT GREEN (-1025 7425);
DISPLAY INVISIBLE (-1025 7425);
FORCEADD MOSFET_PCH_GDS_ESD_PROTECTED..1
R 6
(-3325 3050);
FORCEPROP 1 LAST LOCATION PQ12
J 0
(-3150 2900);
DISPLAY 0.489362 (-3150 2900);
PAINT SKYBLUE (-3150 2900);
FORCEPROP 0 LAST $SEC 1
J 0
(-3150 3075);
DISPLAY 0.680851 (-3150 3075);
PAINT MONO (-3150 3075);
DISPLAY INVISIBLE (-3150 3075);
FORCEPROP 0 LAST CDS_SEC 1
J 0
(-3150 3075);
DISPLAY 1.021277 (-3150 3075);
DISPLAY INVISIBLE (-3150 3075);
FORCEPROP 0 LASTPIN (-3300 2750) $PN D
R 1
J 2
(-3310 2740);
DISPLAY 0.489362 (-3310 2740);
PAINT MONO (-3310 2740);
FORCEPROP 0 LASTPIN (-3600 3050) $PN G
J 2
(-3610 3060);
DISPLAY 0.489362 (-3610 3060);
PAINT MONO (-3610 3060);
FORCEPROP 0 LASTPIN (-3300 3350) $PN S
R 1
J 0
(-3310 3360);
DISPLAY 0.489362 (-3310 3360);
PAINT MONO (-3310 3360);
FORCEPROP 2 LAST VALUE PJA3415AE
J 0
(-3150 3002);
DISPLAY 0.489362 (-3150 3002);
PAINT SKYBLUE (-3150 3002);
FORCEPROP 1 LAST MATERIAL IC
J 0
(-3150 3052);
DISPLAY 0.489362 (-3150 3052);
PAINT SKYBLUE (-3150 3052);
FORCEPROP 2 LAST PART_TYPE SMLF
J 0
(-3175 2877);
DISPLAY 1.021277 (-3175 2877);
DISPLAY INVISIBLE (-3175 2877);
FORCEPROP 1 LAST NEEDS_NO_SIZE TRUE
J 0
(-3325 3016);
DISPLAY 0.723404 (-3325 3016);
PAINT GREEN (-3325 3016);
DISPLAY INVISIBLE (-3325 3016);
FORCEPROP 2 LAST CDS_LIB pure_quanta
J 0
(-3325 3050);
DISPLAY INVISIBLE (-3325 3050);
FORCEPROP 1 LAST CDS_LMAN_SYM_OUTLINE -125,150,125,-150
J 0
(-3325 3050);
DISPLAY 0.468085 (-3325 3050);
PAINT GREEN (-3325 3050);
DISPLAY INVISIBLE (-3325 3050);
FORCEPROP 1 LAST PATH I13
J 0
(-3325 3050);
DISPLAY 0.723404 (-3325 3050);
PAINT GREEN (-3325 3050);
DISPLAY INVISIBLE (-3325 3050);
FORCEPROP 1 LAST PART_NUMBER BAM34150008
J 0
(-3150 2952);
DISPLAY 0.489362 (-3150 2952);
PAINT SKYBLUE (-3150 2952);
DISPLAY INVISIBLE (-3150 2952);
FORCEADD Q_RES..2
(-4550 2325);
FORCEPROP 1 LAST LOCATION R6088
J 0
(-4800 2425);
DISPLAY 0.404255 (-4800 2425);
FORCEPROP 0 LAST $SEC 1
J 0
(-4800 2450);
DISPLAY 0.680851 (-4800 2450);
PAINT MONO (-4800 2450);
DISPLAY INVISIBLE (-4800 2450);
FORCEPROP 0 LAST CDS_SEC 1
J 0
(-4800 2450);
DISPLAY 0.680851 (-4800 2450);
DISPLAY INVISIBLE (-4800 2450);
FORCEPROP 1 LASTPIN (-4550 2425) $PN 1
J 0
(-4545 2387);
DISPLAY 0.787234 (-4545 2387);
PAINT MONO (-4545 2387);
FORCEPROP 1 LASTPIN (-4550 2225) $PN 2
J 0
(-4545 2235);
DISPLAY 0.787234 (-4545 2235);
PAINT MONO (-4545 2235);
FORCEPROP 1 LAST VALUE 10K
J 0
(-4800 2375);
DISPLAY 0.404255 (-4800 2375);
FORCEPROP 1 LAST MATERIAL EMPTY
J 0
(-4800 2225);
DISPLAY 0.404255 (-4800 2225);
FORCEPROP 1 LAST TOLERANCE 1%
J 0
(-4795 2325);
DISPLAY 0.404255 (-4795 2325);
FORCEPROP 1 LAST WATTAGE 1/16W
J 0
(-4800 2275);
DISPLAY 0.404255 (-4800 2275);
FORCEPROP 1 LAST PACK_TYPE 0402LF
J 0
(-4800 2125);
DISPLAY 0.404255 (-4800 2125);
FORCEPROP 2 LAST CDS_LIB pure_quanta
J 0
(-4550 2325);
DISPLAY INVISIBLE (-4550 2325);
FORCEPROP 1 LAST PATH I130
J 0
(-4500 2500);
DISPLAY 0.978723 (-4500 2500);
PAINT WHITE (-4500 2500);
DISPLAY INVISIBLE (-4500 2500);
FORCEPROP 1 LAST PART_NUMBER CS31002FB08
J 0
(-4800 2175);
DISPLAY 0.404255 (-4800 2175);
DISPLAY INVISIBLE (-4800 2175);
FORCEADD Q_CAP..2
(-3600 7350);
FORCEPROP 1 LAST LOCATION C5022
J 1
(-3750 7400);
DISPLAY 0.489362 (-3750 7400);
PAINT SKYBLUE (-3750 7400);
FORCEPROP 0 LAST $SEC 1
J 0
(-3650 7450);
DISPLAY 0.680851 (-3650 7450);
PAINT MONO (-3650 7450);
DISPLAY INVISIBLE (-3650 7450);
FORCEPROP 0 LAST CDS_SEC 1
J 0
(-3650 7450);
DISPLAY 1.021277 (-3650 7450);
DISPLAY INVISIBLE (-3650 7450);
FORCEPROP 1 LASTPIN (-3700 7350) $PN 1
J 0
(-3710 7365);
DISPLAY 0.489362 (-3710 7365);
PAINT MONO (-3710 7365);
FORCEPROP 1 LASTPIN (-3500 7350) $PN 2
J 0
(-3515 7365);
DISPLAY 0.489362 (-3515 7365);
PAINT MONO (-3515 7365);
FORCEPROP 1 LAST VOLTAGE 50V
J 0
(-3850 7500);
DISPLAY 0.489362 (-3850 7500);
PAINT SKYBLUE (-3850 7500);
FORCEPROP 1 LAST MATERIAL X7R
J 0
(-3675 7500);
DISPLAY 0.489362 (-3675 7500);
PAINT SKYBLUE (-3675 7500);
FORCEPROP 1 LAST PACK_TYPE 0402
J 1
(-3525 7500);
DISPLAY 0.489362 (-3525 7500);
PAINT SKYBLUE (-3525 7500);
FORCEPROP 1 LAST VALUE 1000PF
J 2
(-3375 7400);
DISPLAY 0.489362 (-3375 7400);
PAINT SKYBLUE (-3375 7400);
FORCEPROP 1 LAST TOLERANCE 5%
J 2
(-3700 7500);
DISPLAY 0.489362 (-3700 7500);
PAINT SKYBLUE (-3700 7500);
FORCEPROP 2 LAST CDS_LIB pure_quanta
J 0
(-3600 7350);
DISPLAY INVISIBLE (-3600 7350);
FORCEPROP 1 LAST PATH I131
J 0
(-3600 7550);
DISPLAY 0.978723 (-3600 7550);
PAINT WHITE (-3600 7550);
DISPLAY INVISIBLE (-3600 7550);
FORCEPROP 1 LAST PART_NUMBER TMP_QCH21006JB10
J 1
(-3675 7525);
DISPLAY 0.489362 (-3675 7525);
PAINT SKYBLUE (-3675 7525);
DISPLAY INVISIBLE (-3675 7525);
FORCEADD UNIVERSAL_GND..1
R 7
(-3900 7350);
FORCEPROP 3 LASTPIN (-3850 7350) SIG_NAME GND\g
J 0
(-3840 7360);
DISPLAY 0.659574 (-3840 7360);
PAINT MONO (-3840 7360);
DISPLAY INVISIBLE (-3840 7360);
FORCEPROP 2 LAST CDS_LIB pure_quanta_power
R 1
J 0
(-3900 7350);
DISPLAY INVISIBLE (-3900 7350);
FORCEPROP 1 LAST HDL_POWER GND
R 1
J 1
(-3975 7375);
DISPLAY 0.872340 (-3975 7375);
PAINT GREEN (-3975 7375);
DISPLAY INVISIBLE (-3975 7375);
FORCEPROP 1 LAST PATH I132
R 1
J 0
(-3900 7425);
DISPLAY 0.872340 (-3900 7425);
PAINT AQUA (-3900 7425);
DISPLAY INVISIBLE (-3900 7425);
FORCEADD Q_CAP..2
(-3450 5550);
FORCEPROP 1 LAST LOCATION C5020
J 1
(-3600 5600);
DISPLAY 0.489362 (-3600 5600);
PAINT SKYBLUE (-3600 5600);
FORCEPROP 0 LAST $SEC 1
J 0
(-3500 5650);
DISPLAY 0.680851 (-3500 5650);
PAINT MONO (-3500 5650);
DISPLAY INVISIBLE (-3500 5650);
FORCEPROP 0 LAST CDS_SEC 1
J 0
(-3500 5650);
DISPLAY 1.021277 (-3500 5650);
DISPLAY INVISIBLE (-3500 5650);
FORCEPROP 1 LASTPIN (-3550 5550) $PN 1
J 0
(-3560 5565);
DISPLAY 0.489362 (-3560 5565);
PAINT MONO (-3560 5565);
FORCEPROP 1 LASTPIN (-3350 5550) $PN 2
J 0
(-3365 5565);
DISPLAY 0.489362 (-3365 5565);
PAINT MONO (-3365 5565);
FORCEPROP 1 LAST VALUE 1000PF
J 2
(-3225 5600);
DISPLAY 0.489362 (-3225 5600);
PAINT SKYBLUE (-3225 5600);
FORCEPROP 1 LAST PACK_TYPE 0402
J 1
(-3400 5650);
DISPLAY 0.489362 (-3400 5650);
PAINT SKYBLUE (-3400 5650);
FORCEPROP 1 LAST TOLERANCE 5%
J 2
(-3575 5650);
DISPLAY 0.489362 (-3575 5650);
PAINT SKYBLUE (-3575 5650);
FORCEPROP 1 LAST MATERIAL X7R
J 0
(-3550 5650);
DISPLAY 0.489362 (-3550 5650);
PAINT SKYBLUE (-3550 5650);
FORCEPROP 1 LAST VOLTAGE 50V
J 0
(-3725 5650);
DISPLAY 0.489362 (-3725 5650);
PAINT SKYBLUE (-3725 5650);
FORCEPROP 2 LAST CDS_LIB pure_quanta
J 0
(-3450 5550);
DISPLAY INVISIBLE (-3450 5550);
FORCEPROP 1 LAST PATH I133
J 0
(-3450 5750);
DISPLAY 0.978723 (-3450 5750);
PAINT WHITE (-3450 5750);
DISPLAY INVISIBLE (-3450 5750);
FORCEPROP 1 LAST PART_NUMBER TMP_QCH21006JB10
J 1
(-3550 5675);
DISPLAY 0.489362 (-3550 5675);
PAINT SKYBLUE (-3550 5675);
DISPLAY INVISIBLE (-3550 5675);
FORCEADD UNIVERSAL_GND..1
R 7
(-3750 5550);
FORCEPROP 3 LASTPIN (-3700 5550) SIG_NAME GND\g
J 0
(-3690 5560);
DISPLAY 0.659574 (-3690 5560);
PAINT MONO (-3690 5560);
DISPLAY INVISIBLE (-3690 5560);
FORCEPROP 2 LAST CDS_LIB pure_quanta_power
R 1
J 0
(-3750 5550);
DISPLAY INVISIBLE (-3750 5550);
FORCEPROP 1 LAST HDL_POWER GND
R 1
J 1
(-3825 5575);
DISPLAY 0.872340 (-3825 5575);
PAINT GREEN (-3825 5575);
DISPLAY INVISIBLE (-3825 5575);
FORCEPROP 1 LAST PATH I134
R 1
J 0
(-3750 5625);
DISPLAY 0.872340 (-3750 5625);
PAINT AQUA (-3750 5625);
DISPLAY INVISIBLE (-3750 5625);
FORCEADD UNIVERSAL_GND..1
R 7
(-3925 2100);
FORCEPROP 3 LASTPIN (-3875 2100) SIG_NAME GND\g
J 0
(-3865 2110);
DISPLAY 0.659574 (-3865 2110);
PAINT MONO (-3865 2110);
DISPLAY INVISIBLE (-3865 2110);
FORCEPROP 2 LAST CDS_LIB pure_quanta_power
R 1
J 0
(-3925 2100);
DISPLAY INVISIBLE (-3925 2100);
FORCEPROP 1 LAST HDL_POWER GND
R 1
J 1
(-4000 2125);
DISPLAY 0.872340 (-4000 2125);
PAINT GREEN (-4000 2125);
DISPLAY INVISIBLE (-4000 2125);
FORCEPROP 1 LAST PATH I135
R 1
J 0
(-3925 2175);
DISPLAY 0.872340 (-3925 2175);
PAINT AQUA (-3925 2175);
DISPLAY INVISIBLE (-3925 2175);
FORCEADD Q_CAP..2
(-3625 2100);
FORCEPROP 1 LAST LOCATION C5006
J 1
(-3800 2100);
DISPLAY 0.489362 (-3800 2100);
PAINT SKYBLUE (-3800 2100);
FORCEPROP 0 LAST $SEC 1
J 0
(-3675 2200);
DISPLAY 0.680851 (-3675 2200);
PAINT MONO (-3675 2200);
DISPLAY INVISIBLE (-3675 2200);
FORCEPROP 0 LAST CDS_SEC 1
J 0
(-3675 2200);
DISPLAY 1.021277 (-3675 2200);
DISPLAY INVISIBLE (-3675 2200);
FORCEPROP 1 LASTPIN (-3725 2100) $PN 1
J 0
(-3735 2115);
DISPLAY 0.489362 (-3735 2115);
PAINT MONO (-3735 2115);
FORCEPROP 1 LASTPIN (-3525 2100) $PN 2
J 0
(-3540 2115);
DISPLAY 0.489362 (-3540 2115);
PAINT MONO (-3540 2115);
FORCEPROP 1 LAST VOLTAGE 50V
J 0
(-4050 2150);
DISPLAY 0.489362 (-4050 2150);
PAINT SKYBLUE (-4050 2150);
FORCEPROP 1 LAST MATERIAL X7R
J 0
(-3875 2150);
DISPLAY 0.489362 (-3875 2150);
PAINT SKYBLUE (-3875 2150);
FORCEPROP 1 LAST PACK_TYPE 0402
J 1
(-3725 2150);
DISPLAY 0.489362 (-3725 2150);
PAINT SKYBLUE (-3725 2150);
FORCEPROP 1 LAST VALUE 1000PF
J 2
(-3350 2100);
DISPLAY 0.489362 (-3350 2100);
PAINT SKYBLUE (-3350 2100);
FORCEPROP 1 LAST TOLERANCE 5%
J 2
(-3900 2150);
DISPLAY 0.489362 (-3900 2150);
PAINT SKYBLUE (-3900 2150);
FORCEPROP 2 LAST CDS_LIB pure_quanta
J 0
(-3625 2100);
DISPLAY INVISIBLE (-3625 2100);
FORCEPROP 1 LAST PATH I136
J 0
(-3625 2300);
DISPLAY 0.978723 (-3625 2300);
PAINT WHITE (-3625 2300);
DISPLAY INVISIBLE (-3625 2300);
FORCEPROP 1 LAST PART_NUMBER TMP_QCH21006JB10
J 1
(-3875 2175);
DISPLAY 0.489362 (-3875 2175);
PAINT SKYBLUE (-3875 2175);
DISPLAY INVISIBLE (-3875 2175);
FORCEADD Q_RES..1
(-2875 6775);
FORCEPROP 1 LAST LOCATION PR8011
J 0
(-2925 6825);
DISPLAY 0.489362 (-2925 6825);
PAINT SKYBLUE (-2925 6825);
FORCEPROP 0 LAST $SEC 1
J 0
(-2475 6900);
DISPLAY 0.680851 (-2475 6900);
PAINT MONO (-2475 6900);
DISPLAY INVISIBLE (-2475 6900);
FORCEPROP 0 LAST CDS_SEC 1
J 0
(-2475 6900);
DISPLAY 0.680851 (-2475 6900);
DISPLAY INVISIBLE (-2475 6900);
FORCEPROP 1 LASTPIN (-2975 6775) $PN 1
J 0
(-2963 6787);
DISPLAY 0.787234 (-2963 6787);
PAINT MONO (-2963 6787);
FORCEPROP 1 LASTPIN (-2775 6775) $PN 2
J 0
(-2813 6787);
DISPLAY 0.787234 (-2813 6787);
PAINT MONO (-2813 6787);
FORCEPROP 1 LAST VALUE 0
J 2
(-2350 6825);
DISPLAY 0.489362 (-2350 6825);
PAINT SKYBLUE (-2350 6825);
FORCEPROP 1 LAST TOLERANCE 5%
J 0
(-2325 6825);
DISPLAY 0.489362 (-2325 6825);
PAINT SKYBLUE (-2325 6825);
FORCEPROP 1 LAST PACK_TYPE 0402LF
J 0
(-2250 6825);
DISPLAY 0.489362 (-2250 6825);
PAINT SKYBLUE (-2250 6825);
FORCEPROP 1 LAST MATERIAL CHIP
J 0
(-2750 6875);
DISPLAY 0.489362 (-2750 6875);
PAINT SKYBLUE (-2750 6875);
FORCEPROP 1 LAST WATTAGE 1/16W
J 2
(-2475 6875);
DISPLAY 0.489362 (-2475 6875);
PAINT SKYBLUE (-2475 6875);
FORCEPROP 2 LAST CDS_LIB pure_quanta
J 0
(-2875 6775);
DISPLAY INVISIBLE (-2875 6775);
FORCEPROP 1 LAST PATH I137
J 0
(-2925 6925);
DISPLAY 0.978723 (-2925 6925);
PAINT WHITE (-2925 6925);
DISPLAY INVISIBLE (-2925 6925);
FORCEPROP 1 LAST PART_NUMBER CS00002JB13
J 0
(-2750 6825);
DISPLAY 0.489362 (-2750 6825);
PAINT SKYBLUE (-2750 6825);
DISPLAY INVISIBLE (-2750 6825);
FORCEADD Q_RES..1
(-2875 6625);
FORCEPROP 1 LAST LOCATION PR8012
J 0
(-2925 6675);
DISPLAY 0.489362 (-2925 6675);
PAINT SKYBLUE (-2925 6675);
FORCEPROP 0 LAST $SEC 1
J 0
(-2475 6750);
DISPLAY 0.680851 (-2475 6750);
PAINT MONO (-2475 6750);
DISPLAY INVISIBLE (-2475 6750);
FORCEPROP 0 LAST CDS_SEC 1
J 0
(-2475 6750);
DISPLAY 0.680851 (-2475 6750);
DISPLAY INVISIBLE (-2475 6750);
FORCEPROP 1 LASTPIN (-2975 6625) $PN 1
J 0
(-2963 6637);
DISPLAY 0.787234 (-2963 6637);
PAINT MONO (-2963 6637);
FORCEPROP 1 LASTPIN (-2775 6625) $PN 2
J 0
(-2813 6637);
DISPLAY 0.787234 (-2813 6637);
PAINT MONO (-2813 6637);
FORCEPROP 1 LAST WATTAGE 1/16W
J 2
(-2475 6725);
DISPLAY 0.489362 (-2475 6725);
PAINT SKYBLUE (-2475 6725);
FORCEPROP 1 LAST MATERIAL CHIP
J 0
(-2750 6725);
DISPLAY 0.489362 (-2750 6725);
PAINT SKYBLUE (-2750 6725);
FORCEPROP 1 LAST VALUE 0
J 2
(-2350 6675);
DISPLAY 0.489362 (-2350 6675);
PAINT SKYBLUE (-2350 6675);
FORCEPROP 1 LAST TOLERANCE 5%
J 0
(-2325 6675);
DISPLAY 0.489362 (-2325 6675);
PAINT SKYBLUE (-2325 6675);
FORCEPROP 1 LAST PACK_TYPE 0402LF
J 0
(-2250 6675);
DISPLAY 0.489362 (-2250 6675);
PAINT SKYBLUE (-2250 6675);
FORCEPROP 2 LAST CDS_LIB pure_quanta
J 0
(-2875 6625);
DISPLAY INVISIBLE (-2875 6625);
FORCEPROP 1 LAST PATH I138
J 0
(-2925 6775);
DISPLAY 0.978723 (-2925 6775);
PAINT WHITE (-2925 6775);
DISPLAY INVISIBLE (-2925 6775);
FORCEPROP 1 LAST PART_NUMBER CS00002JB13
J 0
(-2750 6675);
DISPLAY 0.489362 (-2750 6675);
PAINT SKYBLUE (-2750 6675);
DISPLAY INVISIBLE (-2750 6675);
FORCEADD OFFPAGE..1
(-4750 3750);
FORCEPROP 2 LAST $XR0 54 
J 0
(-5061 3750);
DISPLAY 0.638298 (-5061 3750);
PAINT MONO (-5061 3750);
FORCEPROP 2 LAST CDS_LIB standard
J 0
(-4750 3750);
DISPLAY INVISIBLE (-4750 3750);
FORCEPROP 1 LAST OFFPAGE TRUE
J 0
(-4425 3625);
DISPLAY 0.872340 (-4425 3625);
PAINT GREEN (-4425 3625);
DISPLAY INVISIBLE (-4425 3625);
FORCEPROP 1 LAST COMMENT_BODY TRUE
J 0
(-4625 3650);
DISPLAY 0.872340 (-4625 3650);
PAINT GREEN (-4625 3650);
DISPLAY INVISIBLE (-4625 3650);
FORCEPROP 2 LAST PATH I14
J 0
(-5050 3800);
DISPLAY 0.680851 (-5050 3800);
DISPLAY INVISIBLE (-5050 3800);
FORCEADD OFFPAGE..1
(-4750 4125);
FORCEPROP 2 LAST $XR0 54 
J 0
(-5061 4125);
DISPLAY 0.638298 (-5061 4125);
PAINT MONO (-5061 4125);
FORCEPROP 2 LAST CDS_LIB standard
J 0
(-4750 4125);
DISPLAY INVISIBLE (-4750 4125);
FORCEPROP 1 LAST OFFPAGE TRUE
J 0
(-4425 4000);
DISPLAY 0.872340 (-4425 4000);
PAINT GREEN (-4425 4000);
DISPLAY INVISIBLE (-4425 4000);
FORCEPROP 1 LAST COMMENT_BODY TRUE
J 0
(-4625 4025);
DISPLAY 0.872340 (-4625 4025);
PAINT GREEN (-4625 4025);
DISPLAY INVISIBLE (-4625 4025);
FORCEPROP 2 LAST PATH I15
J 0
(-5050 4175);
DISPLAY 0.680851 (-5050 4175);
DISPLAY INVISIBLE (-5050 4175);
FORCEADD OFFPAGE..1
(-4750 4850);
FORCEPROP 2 LAST $XR1 224 
J 0
(-5151 4850);
DISPLAY 0.638298 (-5151 4850);
PAINT MONO (-5151 4850);
FORCEPROP 2 LAST $XR0 54 
J 0
(-5031 4850);
DISPLAY 0.638298 (-5031 4850);
PAINT MONO (-5031 4850);
FORCEPROP 2 LAST CDS_LIB standard
J 0
(-4750 4850);
DISPLAY INVISIBLE (-4750 4850);
FORCEPROP 1 LAST OFFPAGE TRUE
J 0
(-4425 4725);
DISPLAY 0.872340 (-4425 4725);
PAINT GREEN (-4425 4725);
DISPLAY INVISIBLE (-4425 4725);
FORCEPROP 1 LAST COMMENT_BODY TRUE
J 0
(-4625 4750);
DISPLAY 0.872340 (-4625 4750);
PAINT GREEN (-4625 4750);
DISPLAY INVISIBLE (-4625 4750);
FORCEPROP 2 LAST PATH I16
J 0
(-5025 4900);
DISPLAY 0.680851 (-5025 4900);
DISPLAY INVISIBLE (-5025 4900);
FORCEADD Q_RES..2
(-4000 3250);
FORCEPROP 1 LAST LOCATION PR232
J 0
(-3950 3375);
DISPLAY 0.489362 (-3950 3375);
PAINT SKYBLUE (-3950 3375);
FORCEPROP 0 LAST $SEC 1
J 0
(-3950 3400);
DISPLAY 0.680851 (-3950 3400);
PAINT MONO (-3950 3400);
DISPLAY INVISIBLE (-3950 3400);
FORCEPROP 0 LAST CDS_SEC 1
J 0
(-4250 3350);
DISPLAY 1.021277 (-4250 3350);
DISPLAY INVISIBLE (-4250 3350);
FORCEPROP 1 LASTPIN (-4000 3350) $PN 1
J 0
(-3995 3312);
DISPLAY 0.489362 (-3995 3312);
PAINT MONO (-3995 3312);
FORCEPROP 1 LASTPIN (-4000 3150) $PN 2
J 0
(-3995 3160);
DISPLAY 0.489362 (-3995 3160);
PAINT MONO (-3995 3160);
FORCEPROP 1 LAST WATTAGE 1/16W
J 0
(-3950 3225);
DISPLAY 0.489362 (-3950 3225);
PAINT SKYBLUE (-3950 3225);
FORCEPROP 1 LAST MATERIAL CHIP
J 0
(-3950 3175);
DISPLAY 0.489362 (-3950 3175);
PAINT SKYBLUE (-3950 3175);
FORCEPROP 1 LAST TOLERANCE 1%
J 0
(-3950 3275);
DISPLAY 0.489362 (-3950 3275);
PAINT SKYBLUE (-3950 3275);
FORCEPROP 1 LAST VALUE 1K
J 0
(-3950 3325);
DISPLAY 0.489362 (-3950 3325);
PAINT SKYBLUE (-3950 3325);
FORCEPROP 1 LAST PACK_TYPE 0402LF
J 0
(-3950 3125);
DISPLAY 0.489362 (-3950 3125);
PAINT SKYBLUE (-3950 3125);
FORCEPROP 2 LAST CDS_LIB pure_quanta
J 0
(-4000 3250);
DISPLAY INVISIBLE (-4000 3250);
FORCEPROP 1 LAST PATH I17
J 0
(-3950 3425);
DISPLAY 0.978723 (-3950 3425);
PAINT WHITE (-3950 3425);
DISPLAY INVISIBLE (-3950 3425);
FORCEPROP 1 LAST PART_NUMBER CS21002FB06
J 0
(-3975 3075);
DISPLAY 0.489362 (-3975 3075);
PAINT SKYBLUE (-3975 3075);
DISPLAY INVISIBLE (-3975 3075);
FORCEADD VCC_CORE..1
(-4000 3500);
FORCEPROP 3 LASTPIN (-4000 3450) SIG_NAME P3V3_AUX\g
J 0
(-3990 3460);
DISPLAY 0.659574 (-3990 3460);
PAINT MONO (-3990 3460);
DISPLAY INVISIBLE (-3990 3460);
FORCEPROP 1 LAST HDL_POWER P3V3_AUX
J 1
(-4000 3550);
DISPLAY 0.489362 (-4000 3550);
PAINT GREEN (-4000 3550);
FORCEPROP 2 LAST CDS_LIB pure_quanta_power
J 0
(-4000 3500);
DISPLAY INVISIBLE (-4000 3500);
FORCEPROP 1 LAST PATH I18
J 0
(-3950 3525);
DISPLAY 0.872340 (-3950 3525);
PAINT AQUA (-3950 3525);
DISPLAY INVISIBLE (-3950 3525);
FORCEADD Q_RES..1
(-3425 3600);
FORCEPROP 1 LAST LOCATION PR460
J 0
(-3475 3675);
DISPLAY 0.489362 (-3475 3675);
PAINT SKYBLUE (-3475 3675);
FORCEPROP 0 LAST $SEC 1
J 0
(-3050 3725);
DISPLAY 0.680851 (-3050 3725);
PAINT MONO (-3050 3725);
DISPLAY INVISIBLE (-3050 3725);
FORCEPROP 0 LAST CDS_SEC 1
J 0
(-3050 3725);
DISPLAY 1.021277 (-3050 3725);
DISPLAY INVISIBLE (-3050 3725);
FORCEPROP 1 LASTPIN (-3525 3600) $PN 1
J 0
(-3513 3612);
DISPLAY 0.489362 (-3513 3612);
PAINT MONO (-3513 3612);
FORCEPROP 1 LASTPIN (-3325 3600) $PN 2
J 0
(-3363 3612);
DISPLAY 0.489362 (-3363 3612);
PAINT MONO (-3363 3612);
FORCEPROP 1 LAST WATTAGE 1/16W
J 2
(-3200 3625);
DISPLAY 0.489362 (-3200 3625);
PAINT SKYBLUE (-3200 3625);
FORCEPROP 1 LAST MATERIAL CHIP
J 0
(-3300 3575);
DISPLAY 0.489362 (-3300 3575);
PAINT SKYBLUE (-3300 3575);
FORCEPROP 1 LAST PACK_TYPE 0402LF
J 0
(-3325 3525);
DISPLAY 0.489362 (-3325 3525);
PAINT SKYBLUE (-3325 3525);
FORCEPROP 1 LAST TOLERANCE 1%
J 0
(-3400 3525);
DISPLAY 0.489362 (-3400 3525);
PAINT SKYBLUE (-3400 3525);
FORCEPROP 1 LAST VALUE 49.9
J 2
(-3375 3625);
DISPLAY 0.489362 (-3375 3625);
PAINT SKYBLUE (-3375 3625);
FORCEPROP 2 LAST CDS_LIB pure_quanta
J 0
(-3425 3600);
DISPLAY INVISIBLE (-3425 3600);
FORCEPROP 1 LAST PATH I19
J 0
(-3475 3750);
DISPLAY 0.978723 (-3475 3750);
PAINT WHITE (-3475 3750);
DISPLAY INVISIBLE (-3475 3750);
FORCEPROP 1 LAST PART_NUMBER CS04992FB07
J 0
(-3675 3550);
DISPLAY 0.489362 (-3675 3550);
PAINT SKYBLUE (-3675 3550);
DISPLAY INVISIBLE (-3675 3550);
FORCEADD Q_RES..1
(-4700 2575);
FORCEPROP 1 LAST LOCATION R8224
J 0
(-4825 2625);
DISPLAY 0.489362 (-4825 2625);
PAINT SKYBLUE (-4825 2625);
FORCEPROP 0 LAST $SEC 1
J 0
(-4350 2725);
DISPLAY 0.680851 (-4350 2725);
PAINT MONO (-4350 2725);
DISPLAY INVISIBLE (-4350 2725);
FORCEPROP 0 LAST CDS_SEC 1
J 0
(-4350 2725);
DISPLAY 1.021277 (-4350 2725);
DISPLAY INVISIBLE (-4350 2725);
FORCEPROP 1 LASTPIN (-4800 2575) $PN 1
J 0
(-4788 2587);
DISPLAY 0.489362 (-4788 2587);
PAINT MONO (-4788 2587);
FORCEPROP 1 LASTPIN (-4600 2575) $PN 2
J 0
(-4638 2587);
DISPLAY 0.489362 (-4638 2587);
PAINT MONO (-4638 2587);
FORCEPROP 1 LAST TOLERANCE 5%
J 0
(-4775 2675);
DISPLAY 0.489362 (-4775 2675);
PAINT SKYBLUE (-4775 2675);
FORCEPROP 1 LAST PACK_TYPE 0402LF
J 0
(-4700 2675);
DISPLAY 0.489362 (-4700 2675);
PAINT SKYBLUE (-4700 2675);
FORCEPROP 1 LAST WATTAGE 1/16W
J 2
(-4575 2775);
DISPLAY 0.489362 (-4575 2775);
PAINT SKYBLUE (-4575 2775);
FORCEPROP 1 LAST MATERIAL CHIP
J 0
(-4825 2775);
DISPLAY 0.489362 (-4825 2775);
PAINT SKYBLUE (-4825 2775);
FORCEPROP 1 LAST VALUE 0
J 2
(-4625 2625);
DISPLAY 0.489362 (-4625 2625);
PAINT SKYBLUE (-4625 2625);
FORCEPROP 2 LAST CDS_LIB pure_quanta
J 0
(-4700 2575);
DISPLAY INVISIBLE (-4700 2575);
FORCEPROP 1 LAST PATH I2
J 0
(-4750 2725);
DISPLAY 0.978723 (-4750 2725);
PAINT WHITE (-4750 2725);
DISPLAY INVISIBLE (-4750 2725);
FORCEPROP 1 LAST PART_NUMBER CS00002JB13
J 0
(-4825 2725);
DISPLAY 0.489362 (-4825 2725);
PAINT SKYBLUE (-4825 2725);
DISPLAY INVISIBLE (-4825 2725);
FORCEADD OFFPAGE..5
(-2875 3225);
FORCEPROP 2 LAST $XR0 82 
J 0
(-3129 3225);
DISPLAY 0.638298 (-3129 3225);
PAINT MONO (-3129 3225);
FORCEPROP 2 LAST CDS_LIB standard
J 0
(-2875 3225);
DISPLAY INVISIBLE (-2875 3225);
FORCEPROP 1 LAST OFFPAGE TRUE
J 0
(-2550 3100);
DISPLAY 0.872340 (-2550 3100);
PAINT GREEN (-2550 3100);
DISPLAY INVISIBLE (-2550 3100);
FORCEPROP 1 LAST COMMENT_BODY TRUE
J 0
(-2775 3150);
DISPLAY 0.872340 (-2775 3150);
PAINT GREEN (-2775 3150);
DISPLAY INVISIBLE (-2775 3150);
FORCEPROP 2 LAST PATH I20
J 0
(-3125 3275);
DISPLAY 0.680851 (-3125 3275);
DISPLAY INVISIBLE (-3125 3275);
FORCEADD OFFPAGE..1
(-2875 3375);
FORCEPROP 2 LAST $XR0 78 
J 0
(-3096 3375);
DISPLAY 0.638298 (-3096 3375);
PAINT MONO (-3096 3375);
FORCEPROP 2 LAST CDS_LIB standard
J 0
(-2875 3375);
DISPLAY INVISIBLE (-2875 3375);
FORCEPROP 1 LAST OFFPAGE TRUE
J 0
(-2550 3250);
DISPLAY 0.872340 (-2550 3250);
PAINT GREEN (-2550 3250);
DISPLAY INVISIBLE (-2550 3250);
FORCEPROP 1 LAST COMMENT_BODY TRUE
J 0
(-2750 3275);
DISPLAY 0.872340 (-2750 3275);
PAINT GREEN (-2750 3275);
DISPLAY INVISIBLE (-2750 3275);
FORCEPROP 2 LAST PATH I21
J 0
(-3075 3425);
DISPLAY 0.680851 (-3075 3425);
DISPLAY INVISIBLE (-3075 3425);
FORCEADD Q_RES..1
(-3400 4275);
FORCEPROP 1 LAST LOCATION PR227
J 0
(-3450 4350);
DISPLAY 0.489362 (-3450 4350);
PAINT SKYBLUE (-3450 4350);
FORCEPROP 0 LAST $SEC 1
J 0
(-3025 4400);
DISPLAY 0.680851 (-3025 4400);
PAINT MONO (-3025 4400);
DISPLAY INVISIBLE (-3025 4400);
FORCEPROP 0 LAST CDS_SEC 1
J 0
(-3025 4400);
DISPLAY 1.021277 (-3025 4400);
DISPLAY INVISIBLE (-3025 4400);
FORCEPROP 1 LASTPIN (-3500 4275) $PN 1
J 0
(-3488 4287);
DISPLAY 0.489362 (-3488 4287);
PAINT MONO (-3488 4287);
FORCEPROP 1 LASTPIN (-3300 4275) $PN 2
J 0
(-3338 4287);
DISPLAY 0.489362 (-3338 4287);
PAINT MONO (-3338 4287);
FORCEPROP 1 LAST VALUE 49.9
J 2
(-3350 4300);
DISPLAY 0.489362 (-3350 4300);
PAINT SKYBLUE (-3350 4300);
FORCEPROP 1 LAST PACK_TYPE 0402LF
J 0
(-3100 4275);
DISPLAY 0.489362 (-3100 4275);
PAINT SKYBLUE (-3100 4275);
FORCEPROP 1 LAST TOLERANCE 1%
J 0
(-3175 4275);
DISPLAY 0.489362 (-3175 4275);
PAINT SKYBLUE (-3175 4275);
FORCEPROP 1 LAST MATERIAL CHIP
J 0
(-3275 4375);
DISPLAY 0.489362 (-3275 4375);
PAINT SKYBLUE (-3275 4375);
FORCEPROP 1 LAST WATTAGE 1/16W
J 2
(-3025 4375);
DISPLAY 0.489362 (-3025 4375);
PAINT SKYBLUE (-3025 4375);
FORCEPROP 2 LAST CDS_LIB pure_quanta
J 0
(-3400 4275);
DISPLAY INVISIBLE (-3400 4275);
FORCEPROP 1 LAST PATH I22
J 0
(-3450 4425);
DISPLAY 0.978723 (-3450 4425);
PAINT WHITE (-3450 4425);
DISPLAY INVISIBLE (-3450 4425);
FORCEPROP 1 LAST PART_NUMBER CS04992FB07
J 0
(-3275 4325);
DISPLAY 0.489362 (-3275 4325);
PAINT SKYBLUE (-3275 4325);
DISPLAY INVISIBLE (-3275 4325);
FORCEADD Q_RES..1
(-3400 4700);
FORCEPROP 1 LAST LOCATION PR226
J 0
(-3450 4775);
DISPLAY 0.489362 (-3450 4775);
PAINT SKYBLUE (-3450 4775);
FORCEPROP 0 LAST $SEC 1
J 0
(-3025 4825);
DISPLAY 0.680851 (-3025 4825);
PAINT MONO (-3025 4825);
DISPLAY INVISIBLE (-3025 4825);
FORCEPROP 0 LAST CDS_SEC 1
J 0
(-3025 4825);
DISPLAY 1.021277 (-3025 4825);
DISPLAY INVISIBLE (-3025 4825);
FORCEPROP 1 LASTPIN (-3500 4700) $PN 1
J 0
(-3488 4712);
DISPLAY 0.489362 (-3488 4712);
PAINT MONO (-3488 4712);
FORCEPROP 1 LASTPIN (-3300 4700) $PN 2
J 0
(-3338 4712);
DISPLAY 0.489362 (-3338 4712);
PAINT MONO (-3338 4712);
FORCEPROP 1 LAST WATTAGE 1/16W
J 2
(-3150 4725);
DISPLAY 0.489362 (-3150 4725);
PAINT SKYBLUE (-3150 4725);
FORCEPROP 1 LAST VALUE 49.9
J 2
(-3350 4725);
DISPLAY 0.489362 (-3350 4725);
PAINT SKYBLUE (-3350 4725);
FORCEPROP 1 LAST MATERIAL CHIP
J 0
(-3275 4650);
DISPLAY 0.489362 (-3275 4650);
PAINT SKYBLUE (-3275 4650);
FORCEPROP 1 LAST TOLERANCE 1%
J 0
(-3600 4725);
DISPLAY 0.489362 (-3600 4725);
PAINT SKYBLUE (-3600 4725);
FORCEPROP 1 LAST PACK_TYPE 0402LF
J 0
(-3300 4600);
DISPLAY 0.489362 (-3300 4600);
PAINT SKYBLUE (-3300 4600);
FORCEPROP 2 LAST CDS_LIB pure_quanta
J 0
(-3400 4700);
DISPLAY INVISIBLE (-3400 4700);
FORCEPROP 1 LAST PATH I23
J 0
(-3450 4850);
DISPLAY 0.978723 (-3450 4850);
PAINT WHITE (-3450 4850);
DISPLAY INVISIBLE (-3450 4850);
FORCEPROP 1 LAST PART_NUMBER CS04992FB07
J 0
(-3675 4650);
DISPLAY 0.489362 (-3675 4650);
PAINT SKYBLUE (-3675 4650);
DISPLAY INVISIBLE (-3675 4650);
FORCEADD OFFPAGE..5
(-5025 6475);
FORCEPROP 2 LAST $XR0 54 
J 0
(-5279 6475);
DISPLAY 0.638298 (-5279 6475);
PAINT MONO (-5279 6475);
FORCEPROP 2 LAST CDS_LIB standard
J 0
(-5025 6475);
DISPLAY INVISIBLE (-5025 6475);
FORCEPROP 1 LAST OFFPAGE TRUE
J 0
(-4700 6350);
DISPLAY 0.872340 (-4700 6350);
PAINT GREEN (-4700 6350);
DISPLAY INVISIBLE (-4700 6350);
FORCEPROP 1 LAST COMMENT_BODY TRUE
J 0
(-4925 6400);
DISPLAY 0.872340 (-4925 6400);
PAINT GREEN (-4925 6400);
DISPLAY INVISIBLE (-4925 6400);
FORCEPROP 2 LAST PATH I24
J 0
(-5225 6525);
DISPLAY 0.680851 (-5225 6525);
DISPLAY INVISIBLE (-5225 6525);
FORCEADD OFFPAGE..1
(-5025 6625);
FORCEPROP 2 LAST $XR0 54 
J 0
(-5246 6625);
DISPLAY 0.638298 (-5246 6625);
PAINT MONO (-5246 6625);
FORCEPROP 2 LAST CDS_LIB standard
J 0
(-5025 6625);
DISPLAY INVISIBLE (-5025 6625);
FORCEPROP 1 LAST OFFPAGE TRUE
J 0
(-4700 6500);
DISPLAY 0.872340 (-4700 6500);
PAINT GREEN (-4700 6500);
DISPLAY INVISIBLE (-4700 6500);
FORCEPROP 1 LAST COMMENT_BODY TRUE
J 0
(-4900 6525);
DISPLAY 0.872340 (-4900 6525);
PAINT GREEN (-4900 6525);
DISPLAY INVISIBLE (-4900 6525);
FORCEPROP 2 LAST PATH I25
J 0
(-5225 6675);
DISPLAY 0.680851 (-5225 6675);
DISPLAY INVISIBLE (-5225 6675);
FORCEADD OFFPAGE..1
(-5025 6775);
FORCEPROP 2 LAST $XR0 54 
J 0
(-5246 6775);
DISPLAY 0.638298 (-5246 6775);
PAINT MONO (-5246 6775);
FORCEPROP 2 LAST CDS_LIB standard
J 0
(-5025 6775);
DISPLAY INVISIBLE (-5025 6775);
FORCEPROP 1 LAST OFFPAGE TRUE
J 0
(-4700 6650);
DISPLAY 0.872340 (-4700 6650);
PAINT GREEN (-4700 6650);
DISPLAY INVISIBLE (-4700 6650);
FORCEPROP 1 LAST COMMENT_BODY TRUE
J 0
(-4900 6675);
DISPLAY 0.872340 (-4900 6675);
PAINT GREEN (-4900 6675);
DISPLAY INVISIBLE (-4900 6675);
FORCEPROP 2 LAST PATH I26
J 0
(-5225 6825);
DISPLAY 0.680851 (-5225 6825);
DISPLAY INVISIBLE (-5225 6825);
FORCEADD OFFPAGE..1
(-4750 5225);
FORCEPROP 2 LAST $XR0 54 
J 0
(-5031 5225);
DISPLAY 0.638298 (-5031 5225);
PAINT MONO (-5031 5225);
FORCEPROP 2 LAST CDS_LIB standard
J 0
(-4750 5225);
DISPLAY INVISIBLE (-4750 5225);
FORCEPROP 1 LAST OFFPAGE TRUE
J 0
(-4425 5100);
DISPLAY 0.872340 (-4425 5100);
PAINT GREEN (-4425 5100);
DISPLAY INVISIBLE (-4425 5100);
FORCEPROP 1 LAST COMMENT_BODY TRUE
J 0
(-4625 5125);
DISPLAY 0.872340 (-4625 5125);
PAINT GREEN (-4625 5125);
DISPLAY INVISIBLE (-4625 5125);
FORCEPROP 2 LAST PATH I27
J 0
(-5025 5275);
DISPLAY 0.680851 (-5025 5275);
DISPLAY INVISIBLE (-5025 5275);
FORCEADD UNIVERSAL_GND..1
(-5000 5675);
FORCEPROP 3 LASTPIN (-5000 5725) SIG_NAME GND\g
J 0
(-4990 5735);
DISPLAY 0.659574 (-4990 5735);
PAINT MONO (-4990 5735);
DISPLAY INVISIBLE (-4990 5735);
FORCEPROP 2 LAST CDS_LIB pure_quanta_power
J 0
(-5000 5675);
DISPLAY INVISIBLE (-5000 5675);
FORCEPROP 1 LAST HDL_POWER GND
J 1
(-4975 5600);
DISPLAY 0.872340 (-4975 5600);
PAINT GREEN (-4975 5600);
DISPLAY INVISIBLE (-4975 5600);
FORCEPROP 1 LAST PATH I28
J 0
(-4925 5675);
DISPLAY 0.872340 (-4925 5675);
PAINT AQUA (-4925 5675);
DISPLAY INVISIBLE (-4925 5675);
FORCEADD Q_RES..2
(-5000 6125);
FORCEPROP 1 LAST LOCATION PR217
J 0
(-4955 6250);
DISPLAY 0.489362 (-4955 6250);
PAINT SKYBLUE (-4955 6250);
FORCEPROP 0 LAST $SEC 1
J 0
(-4950 6275);
DISPLAY 0.680851 (-4950 6275);
PAINT MONO (-4950 6275);
DISPLAY INVISIBLE (-4950 6275);
FORCEPROP 0 LAST CDS_SEC 1
J 0
(-4950 6275);
DISPLAY 1.021277 (-4950 6275);
DISPLAY INVISIBLE (-4950 6275);
FORCEPROP 1 LASTPIN (-5000 6225) $PN 1
J 0
(-4995 6187);
DISPLAY 0.489362 (-4995 6187);
PAINT MONO (-4995 6187);
FORCEPROP 1 LASTPIN (-5000 6025) $PN 2
J 0
(-4995 6035);
DISPLAY 0.489362 (-4995 6035);
PAINT MONO (-4995 6035);
FORCEPROP 1 LAST TOLERANCE 5%
J 0
(-4970 6100);
DISPLAY 0.489362 (-4970 6100);
PAINT SKYBLUE (-4970 6100);
FORCEPROP 1 LAST PACK_TYPE 0402LF
J 0
(-4975 5950);
DISPLAY 0.489362 (-4975 5950);
PAINT SKYBLUE (-4975 5950);
FORCEPROP 1 LAST MATERIAL CHIP
J 0
(-4975 6000);
DISPLAY 0.489362 (-4975 6000);
PAINT SKYBLUE (-4975 6000);
FORCEPROP 1 LAST VALUE 0
J 0
(-4970 6150);
DISPLAY 0.489362 (-4970 6150);
PAINT SKYBLUE (-4970 6150);
FORCEPROP 1 LAST WATTAGE 1/16W
J 0
(-4975 6050);
DISPLAY 0.489362 (-4975 6050);
PAINT SKYBLUE (-4975 6050);
FORCEPROP 2 LAST CDS_LIB pure_quanta
J 0
(-5000 6125);
DISPLAY INVISIBLE (-5000 6125);
FORCEPROP 1 LAST PATH I29
J 0
(-4950 6300);
DISPLAY 0.978723 (-4950 6300);
PAINT WHITE (-4950 6300);
DISPLAY INVISIBLE (-4950 6300);
FORCEPROP 1 LAST PART_NUMBER CS00002JB13
J 0
(-5000 5875);
DISPLAY 0.489362 (-5000 5875);
PAINT SKYBLUE (-5000 5875);
DISPLAY INVISIBLE (-5000 5875);
FORCEADD Q_CAP..1
(-4325 2400);
FORCEPROP 1 LAST LOCATION C8356
J 0
(-4275 2500);
DISPLAY 0.489362 (-4275 2500);
PAINT SKYBLUE (-4275 2500);
FORCEPROP 0 LAST $SEC 1
J 0
(-4275 2525);
DISPLAY 0.680851 (-4275 2525);
PAINT MONO (-4275 2525);
DISPLAY INVISIBLE (-4275 2525);
FORCEPROP 0 LAST CDS_SEC 1
J 0
(-4275 2525);
DISPLAY 1.021277 (-4275 2525);
DISPLAY INVISIBLE (-4275 2525);
FORCEPROP 1 LASTPIN (-4325 2500) $PN 1
J 0
(-4315 2480);
DISPLAY 0.489362 (-4315 2480);
PAINT MONO (-4315 2480);
FORCEPROP 1 LASTPIN (-4325 2300) $PN 2
J 0
(-4315 2280);
DISPLAY 0.489362 (-4315 2280);
PAINT MONO (-4315 2280);
FORCEPROP 1 LAST PACK_TYPE 0402
J 0
(-4275 2250);
DISPLAY 0.489362 (-4275 2250);
PAINT SKYBLUE (-4275 2250);
FORCEPROP 1 LAST TOLERANCE 5%
J 0
(-4275 2350);
DISPLAY 0.489362 (-4275 2350);
PAINT SKYBLUE (-4275 2350);
FORCEPROP 1 LAST VOLTAGE 50V
J 0
(-4275 2400);
DISPLAY 0.489362 (-4275 2400);
PAINT SKYBLUE (-4275 2400);
FORCEPROP 1 LAST MATERIAL X7R
J 0
(-4275 2300);
DISPLAY 0.489362 (-4275 2300);
PAINT SKYBLUE (-4275 2300);
FORCEPROP 1 LAST VALUE 1000PF
J 0
(-4275 2450);
DISPLAY 0.489362 (-4275 2450);
PAINT SKYBLUE (-4275 2450);
FORCEPROP 2 LAST CDS_LIB pure_quanta
J 0
(-4325 2400);
DISPLAY INVISIBLE (-4325 2400);
FORCEPROP 1 LAST PATH I3
J 0
(-4275 2550);
DISPLAY 0.978723 (-4275 2550);
PAINT WHITE (-4275 2550);
DISPLAY INVISIBLE (-4275 2550);
FORCEPROP 1 LAST PART_NUMBER TMP_QCH21006JB10
J 0
(-4275 2200);
DISPLAY 0.489362 (-4275 2200);
PAINT SKYBLUE (-4275 2200);
DISPLAY INVISIBLE (-4275 2200);
FORCEADD Q_RES..2
(-4825 6125);
FORCEPROP 1 LAST LOCATION R8219
J 0
(-4780 6250);
DISPLAY 0.489362 (-4780 6250);
PAINT SKYBLUE (-4780 6250);
FORCEPROP 0 LAST $SEC 1
J 0
(-4775 6275);
DISPLAY 0.680851 (-4775 6275);
PAINT MONO (-4775 6275);
DISPLAY INVISIBLE (-4775 6275);
FORCEPROP 0 LAST CDS_SEC 1
J 0
(-4775 6275);
DISPLAY 1.021277 (-4775 6275);
DISPLAY INVISIBLE (-4775 6275);
FORCEPROP 1 LASTPIN (-4825 6225) $PN 1
J 0
(-4820 6187);
DISPLAY 0.489362 (-4820 6187);
PAINT MONO (-4820 6187);
FORCEPROP 1 LASTPIN (-4825 6025) $PN 2
J 0
(-4820 6035);
DISPLAY 0.489362 (-4820 6035);
PAINT MONO (-4820 6035);
FORCEPROP 1 LAST PACK_TYPE 0402LF
J 0
(-4800 5950);
DISPLAY 0.489362 (-4800 5950);
PAINT SKYBLUE (-4800 5950);
FORCEPROP 1 LAST WATTAGE 1/16W
J 0
(-4800 6050);
DISPLAY 0.489362 (-4800 6050);
PAINT SKYBLUE (-4800 6050);
FORCEPROP 1 LAST MATERIAL EMPTY
J 0
(-4800 6000);
DISPLAY 0.489362 (-4800 6000);
PAINT RED (-4800 6000);
FORCEPROP 1 LAST VALUE 1K
J 0
(-4795 6150);
DISPLAY 0.489362 (-4795 6150);
PAINT SKYBLUE (-4795 6150);
FORCEPROP 1 LAST TOLERANCE 1%
J 0
(-4795 6100);
DISPLAY 0.489362 (-4795 6100);
PAINT SKYBLUE (-4795 6100);
FORCEPROP 2 LAST CDS_LIB pure_quanta
J 0
(-4825 6125);
DISPLAY INVISIBLE (-4825 6125);
FORCEPROP 1 LAST PATH I30
J 0
(-4775 6300);
DISPLAY 0.978723 (-4775 6300);
PAINT WHITE (-4775 6300);
DISPLAY INVISIBLE (-4775 6300);
FORCEPROP 1 LAST PART_NUMBER CS21002FB06
J 0
(-4800 5950);
DISPLAY 0.489362 (-4800 5950);
PAINT SKYBLUE (-4800 5950);
DISPLAY INVISIBLE (-4800 5950);
FORCEADD Q_CAP..1
(-4650 6100);
FORCEPROP 1 LAST LOCATION C308
J 0
(-4600 6200);
DISPLAY 0.489362 (-4600 6200);
PAINT SKYBLUE (-4600 6200);
FORCEPROP 0 LAST $SEC 1
J 0
(-4600 6225);
DISPLAY 0.680851 (-4600 6225);
PAINT MONO (-4600 6225);
DISPLAY INVISIBLE (-4600 6225);
FORCEPROP 0 LAST CDS_SEC 1
J 0
(-4600 6225);
DISPLAY 1.021277 (-4600 6225);
DISPLAY INVISIBLE (-4600 6225);
FORCEPROP 1 LASTPIN (-4650 6200) $PN 1
J 0
(-4640 6180);
DISPLAY 0.489362 (-4640 6180);
PAINT MONO (-4640 6180);
FORCEPROP 1 LASTPIN (-4650 6000) $PN 2
J 0
(-4640 5980);
DISPLAY 0.489362 (-4640 5980);
PAINT MONO (-4640 5980);
FORCEPROP 1 LAST PACK_TYPE 0402
J 0
(-4600 5900);
DISPLAY 0.489362 (-4600 5900);
PAINT SKYBLUE (-4600 5900);
FORCEPROP 1 LAST TOLERANCE 5%
J 0
(-4600 6050);
DISPLAY 0.489362 (-4600 6050);
PAINT SKYBLUE (-4600 6050);
FORCEPROP 1 LAST MATERIAL EMPTY
J 0
(-4600 6000);
DISPLAY 0.489362 (-4600 6000);
PAINT RED (-4600 6000);
FORCEPROP 1 LAST VOLTAGE 50V
J 0
(-4600 6100);
DISPLAY 0.489362 (-4600 6100);
PAINT SKYBLUE (-4600 6100);
FORCEPROP 1 LAST VALUE 10PF
J 0
(-4600 6150);
DISPLAY 0.489362 (-4600 6150);
PAINT SKYBLUE (-4600 6150);
FORCEPROP 2 LAST CDS_LIB pure_quanta
J 0
(-4650 6100);
DISPLAY INVISIBLE (-4650 6100);
FORCEPROP 1 LAST PATH I31
J 0
(-4600 6250);
DISPLAY 0.978723 (-4600 6250);
PAINT WHITE (-4600 6250);
DISPLAY INVISIBLE (-4600 6250);
FORCEPROP 1 LAST PART_NUMBER CH01006JB08
J 0
(-4600 5950);
DISPLAY 0.489362 (-4600 5950);
PAINT SKYBLUE (-4600 5950);
DISPLAY INVISIBLE (-4600 5950);
FORCEADD Q_CAP..1
(-4450 6125);
FORCEPROP 1 LAST LOCATION C309
J 0
(-4400 6225);
DISPLAY 0.489362 (-4400 6225);
PAINT SKYBLUE (-4400 6225);
FORCEPROP 0 LAST $SEC 1
J 0
(-4400 6250);
DISPLAY 0.680851 (-4400 6250);
PAINT MONO (-4400 6250);
DISPLAY INVISIBLE (-4400 6250);
FORCEPROP 0 LAST CDS_SEC 1
J 0
(-4400 6250);
DISPLAY 1.021277 (-4400 6250);
DISPLAY INVISIBLE (-4400 6250);
FORCEPROP 1 LASTPIN (-4450 6225) $PN 1
J 0
(-4440 6205);
DISPLAY 0.489362 (-4440 6205);
PAINT MONO (-4440 6205);
FORCEPROP 1 LASTPIN (-4450 6025) $PN 2
J 0
(-4440 6005);
DISPLAY 0.489362 (-4440 6005);
PAINT MONO (-4440 6005);
FORCEPROP 1 LAST VOLTAGE 50V
J 0
(-4400 6125);
DISPLAY 0.489362 (-4400 6125);
PAINT SKYBLUE (-4400 6125);
FORCEPROP 1 LAST PACK_TYPE 0402
J 0
(-4400 5925);
DISPLAY 0.489362 (-4400 5925);
PAINT SKYBLUE (-4400 5925);
FORCEPROP 1 LAST TOLERANCE 5%
J 0
(-4400 6075);
DISPLAY 0.489362 (-4400 6075);
PAINT SKYBLUE (-4400 6075);
FORCEPROP 1 LAST MATERIAL EMPTY
J 0
(-4400 6025);
DISPLAY 0.489362 (-4400 6025);
PAINT RED (-4400 6025);
FORCEPROP 1 LAST VALUE 10PF
J 0
(-4400 6175);
DISPLAY 0.489362 (-4400 6175);
PAINT SKYBLUE (-4400 6175);
FORCEPROP 2 LAST CDS_LIB pure_quanta
J 0
(-4450 6125);
DISPLAY INVISIBLE (-4450 6125);
FORCEPROP 1 LAST PATH I32
J 0
(-4400 6275);
DISPLAY 0.978723 (-4400 6275);
PAINT WHITE (-4400 6275);
DISPLAY INVISIBLE (-4400 6275);
FORCEPROP 1 LAST PART_NUMBER CH01006JB08
J 0
(-4400 5975);
DISPLAY 0.489362 (-4400 5975);
PAINT SKYBLUE (-4400 5975);
DISPLAY INVISIBLE (-4400 5975);
FORCEADD Q_CAP..1
(-4250 6125);
FORCEPROP 1 LAST LOCATION C310
J 0
(-4200 6225);
DISPLAY 0.489362 (-4200 6225);
PAINT SKYBLUE (-4200 6225);
FORCEPROP 0 LAST $SEC 1
J 0
(-4200 6250);
DISPLAY 0.680851 (-4200 6250);
PAINT MONO (-4200 6250);
DISPLAY INVISIBLE (-4200 6250);
FORCEPROP 0 LAST CDS_SEC 1
J 0
(-4200 6250);
DISPLAY 1.021277 (-4200 6250);
DISPLAY INVISIBLE (-4200 6250);
FORCEPROP 1 LASTPIN (-4250 6225) $PN 1
J 0
(-4240 6205);
DISPLAY 0.489362 (-4240 6205);
PAINT MONO (-4240 6205);
FORCEPROP 1 LASTPIN (-4250 6025) $PN 2
J 0
(-4240 6005);
DISPLAY 0.489362 (-4240 6005);
PAINT MONO (-4240 6005);
FORCEPROP 1 LAST VOLTAGE 50V
J 0
(-4200 6125);
DISPLAY 0.489362 (-4200 6125);
PAINT SKYBLUE (-4200 6125);
FORCEPROP 1 LAST TOLERANCE 5%
J 0
(-4200 6075);
DISPLAY 0.489362 (-4200 6075);
PAINT SKYBLUE (-4200 6075);
FORCEPROP 1 LAST PACK_TYPE 0402
J 0
(-4200 5925);
DISPLAY 0.489362 (-4200 5925);
PAINT SKYBLUE (-4200 5925);
FORCEPROP 1 LAST VALUE 10PF
J 0
(-4200 6175);
DISPLAY 0.489362 (-4200 6175);
PAINT SKYBLUE (-4200 6175);
FORCEPROP 1 LAST MATERIAL EMPTY
J 0
(-4200 6025);
DISPLAY 0.489362 (-4200 6025);
PAINT RED (-4200 6025);
FORCEPROP 2 LAST CDS_LIB pure_quanta
J 0
(-4250 6125);
DISPLAY INVISIBLE (-4250 6125);
FORCEPROP 1 LAST PATH I33
J 0
(-4200 6275);
DISPLAY 0.978723 (-4200 6275);
PAINT WHITE (-4200 6275);
DISPLAY INVISIBLE (-4200 6275);
FORCEPROP 1 LAST PART_NUMBER CH01006JB08
J 0
(-4200 5975);
DISPLAY 0.489362 (-4200 5975);
PAINT SKYBLUE (-4200 5975);
DISPLAY INVISIBLE (-4200 5975);
FORCEADD Q_RES..1
(-3350 5375);
FORCEPROP 1 LAST LOCATION PR228
J 0
(-3400 5450);
DISPLAY 0.489362 (-3400 5450);
PAINT SKYBLUE (-3400 5450);
FORCEPROP 0 LAST $SEC 1
J 0
(-2975 5500);
DISPLAY 0.680851 (-2975 5500);
PAINT MONO (-2975 5500);
DISPLAY INVISIBLE (-2975 5500);
FORCEPROP 0 LAST CDS_SEC 1
J 0
(-2975 5500);
DISPLAY 1.021277 (-2975 5500);
DISPLAY INVISIBLE (-2975 5500);
FORCEPROP 1 LASTPIN (-3450 5375) $PN 1
J 0
(-3438 5387);
DISPLAY 0.489362 (-3438 5387);
PAINT MONO (-3438 5387);
FORCEPROP 1 LASTPIN (-3250 5375) $PN 2
J 0
(-3288 5387);
DISPLAY 0.489362 (-3288 5387);
PAINT MONO (-3288 5387);
FORCEPROP 1 LAST PACK_TYPE 0402LF
J 0
(-3275 5275);
DISPLAY 0.489362 (-3275 5275);
PAINT SKYBLUE (-3275 5275);
FORCEPROP 1 LAST MATERIAL CHIP
J 0
(-3250 5325);
DISPLAY 0.489362 (-3250 5325);
PAINT SKYBLUE (-3250 5325);
FORCEPROP 1 LAST VALUE 49.9
J 2
(-3300 5400);
DISPLAY 0.489362 (-3300 5400);
PAINT SKYBLUE (-3300 5400);
FORCEPROP 1 LAST TOLERANCE 1%
J 0
(-3500 5375);
DISPLAY 0.489362 (-3500 5375);
PAINT SKYBLUE (-3500 5375);
FORCEPROP 1 LAST WATTAGE 1/16W
J 2
(-3125 5425);
DISPLAY 0.489362 (-3125 5425);
PAINT SKYBLUE (-3125 5425);
FORCEPROP 2 LAST CDS_LIB pure_quanta
J 0
(-3350 5375);
DISPLAY INVISIBLE (-3350 5375);
FORCEPROP 1 LAST PATH I34
J 0
(-3400 5525);
DISPLAY 0.978723 (-3400 5525);
PAINT WHITE (-3400 5525);
DISPLAY INVISIBLE (-3400 5525);
FORCEPROP 1 LAST PART_NUMBER CS04992FB07
J 0
(-3625 5300);
DISPLAY 0.489362 (-3625 5300);
PAINT SKYBLUE (-3625 5300);
DISPLAY INVISIBLE (-3625 5300);
FORCEADD OFFPAGE..5
(-3150 5775);
FORCEPROP 2 LAST $XR1 82 
J 0
(-3464 5775);
DISPLAY 0.638298 (-3464 5775);
PAINT MONO (-3464 5775);
FORCEPROP 2 LAST $XR0 83 
J 0
(-3374 5775);
DISPLAY 0.638298 (-3374 5775);
PAINT MONO (-3374 5775);
FORCEPROP 2 LAST CDS_LIB standard
J 0
(-3150 5775);
DISPLAY INVISIBLE (-3150 5775);
FORCEPROP 1 LAST OFFPAGE TRUE
J 0
(-2825 5650);
DISPLAY 0.872340 (-2825 5650);
PAINT GREEN (-2825 5650);
DISPLAY INVISIBLE (-2825 5650);
FORCEPROP 1 LAST COMMENT_BODY TRUE
J 0
(-3050 5700);
DISPLAY 0.872340 (-3050 5700);
PAINT GREEN (-3050 5700);
DISPLAY INVISIBLE (-3050 5700);
FORCEPROP 2 LAST PATH I35
J 0
(-3350 5825);
DISPLAY 0.680851 (-3350 5825);
DISPLAY INVISIBLE (-3350 5825);
FORCEADD OFFPAGE..6
(-3150 5925);
FORCEPROP 2 LAST $XR0 151 
J 0
(-3430 5925);
DISPLAY 0.638298 (-3430 5925);
PAINT MONO (-3430 5925);
FORCEPROP 2 LAST CDS_LIB standard
J 0
(-3150 5925);
DISPLAY INVISIBLE (-3150 5925);
FORCEPROP 1 LAST OFFPAGE TRUE
J 0
(-2825 5800);
DISPLAY 0.872340 (-2825 5800);
PAINT GREEN (-2825 5800);
DISPLAY INVISIBLE (-2825 5800);
FORCEPROP 1 LAST COMMENT_BODY TRUE
J 0
(-3050 5850);
DISPLAY 0.872340 (-3050 5850);
PAINT GREEN (-3050 5850);
DISPLAY INVISIBLE (-3050 5850);
FORCEPROP 2 LAST PATH I36
J 0
(-3425 5975);
DISPLAY 0.680851 (-3425 5975);
DISPLAY INVISIBLE (-3425 5975);
FORCEADD OFFPAGE..1
(-3150 6075);
FORCEPROP 2 LAST $XR0 151 
J 0
(-3402 6075);
DISPLAY 0.638298 (-3402 6075);
PAINT MONO (-3402 6075);
FORCEPROP 2 LAST CDS_LIB standard
J 0
(-3150 6075);
DISPLAY INVISIBLE (-3150 6075);
FORCEPROP 1 LAST OFFPAGE TRUE
J 0
(-2825 5950);
DISPLAY 0.872340 (-2825 5950);
PAINT GREEN (-2825 5950);
DISPLAY INVISIBLE (-2825 5950);
FORCEPROP 1 LAST COMMENT_BODY TRUE
J 0
(-3025 5975);
DISPLAY 0.872340 (-3025 5975);
PAINT GREEN (-3025 5975);
DISPLAY INVISIBLE (-3025 5975);
FORCEPROP 2 LAST PATH I37
J 0
(-3425 6125);
DISPLAY 0.680851 (-3425 6125);
DISPLAY INVISIBLE (-3425 6125);
FORCEADD Q_RES..2
(-4950 7100);
FORCEPROP 1 LAST LOCATION PR218
J 0
(-4905 7225);
DISPLAY 0.489362 (-4905 7225);
PAINT SKYBLUE (-4905 7225);
FORCEPROP 0 LAST $SEC 1
J 0
(-4900 7250);
DISPLAY 0.680851 (-4900 7250);
PAINT MONO (-4900 7250);
DISPLAY INVISIBLE (-4900 7250);
FORCEPROP 0 LAST CDS_SEC 1
J 0
(-4900 7250);
DISPLAY 1.021277 (-4900 7250);
DISPLAY INVISIBLE (-4900 7250);
FORCEPROP 1 LASTPIN (-4950 7200) $PN 1
J 0
(-4945 7162);
DISPLAY 0.489362 (-4945 7162);
PAINT MONO (-4945 7162);
FORCEPROP 1 LASTPIN (-4950 7000) $PN 2
J 0
(-4945 7010);
DISPLAY 0.489362 (-4945 7010);
PAINT MONO (-4945 7010);
FORCEPROP 1 LAST WATTAGE 1/16W
J 0
(-4925 7025);
DISPLAY 0.489362 (-4925 7025);
PAINT SKYBLUE (-4925 7025);
FORCEPROP 1 LAST VALUE 1K
J 0
(-4920 7125);
DISPLAY 0.489362 (-4920 7125);
PAINT SKYBLUE (-4920 7125);
FORCEPROP 1 LAST PACK_TYPE 0402LF
J 0
(-4925 6925);
DISPLAY 0.489362 (-4925 6925);
PAINT SKYBLUE (-4925 6925);
FORCEPROP 1 LAST MATERIAL EMPTY
J 0
(-4925 6975);
DISPLAY 0.489362 (-4925 6975);
PAINT RED (-4925 6975);
FORCEPROP 1 LAST TOLERANCE 1%
J 0
(-4920 7075);
DISPLAY 0.489362 (-4920 7075);
PAINT SKYBLUE (-4920 7075);
FORCEPROP 2 LAST CDS_LIB pure_quanta
J 0
(-4950 7100);
DISPLAY INVISIBLE (-4950 7100);
FORCEPROP 1 LAST PATH I38
J 0
(-4900 7275);
DISPLAY 0.978723 (-4900 7275);
PAINT WHITE (-4900 7275);
DISPLAY INVISIBLE (-4900 7275);
FORCEPROP 1 LAST PART_NUMBER CS21002FB06
J 0
(-4925 6925);
DISPLAY 0.489362 (-4925 6925);
PAINT SKYBLUE (-4925 6925);
DISPLAY INVISIBLE (-4925 6925);
FORCEADD VCC_CORE..1
(-4950 7450);
FORCEPROP 3 LASTPIN (-4950 7400) SIG_NAME PVDD18_S5_P1\g
J 0
(-4940 7410);
DISPLAY 0.659574 (-4940 7410);
PAINT MONO (-4940 7410);
DISPLAY INVISIBLE (-4940 7410);
FORCEPROP 1 LAST HDL_POWER PVDD18_S5_P1
J 1
(-4950 7500);
DISPLAY 0.489362 (-4950 7500);
PAINT GREEN (-4950 7500);
FORCEPROP 2 LAST CDS_LIB pure_quanta_power
J 0
(-4950 7450);
DISPLAY INVISIBLE (-4950 7450);
FORCEPROP 1 LAST PATH I39
J 0
(-4900 7475);
DISPLAY 0.872340 (-4900 7475);
PAINT AQUA (-4900 7475);
DISPLAY INVISIBLE (-4900 7475);
FORCEADD UNIVERSAL_GND..1
(-4325 2100);
FORCEPROP 3 LASTPIN (-4325 2150) SIG_NAME GND\g
J 0
(-4315 2160);
DISPLAY 0.659574 (-4315 2160);
PAINT MONO (-4315 2160);
DISPLAY INVISIBLE (-4315 2160);
FORCEPROP 2 LAST CDS_LIB pure_quanta_power
J 0
(-4325 2100);
DISPLAY INVISIBLE (-4325 2100);
FORCEPROP 1 LAST HDL_POWER GND
J 1
(-4300 2025);
DISPLAY 0.872340 (-4300 2025);
PAINT GREEN (-4300 2025);
DISPLAY INVISIBLE (-4300 2025);
FORCEPROP 1 LAST PATH I4
J 0
(-4250 2100);
DISPLAY 0.872340 (-4250 2100);
PAINT AQUA (-4250 2100);
DISPLAY INVISIBLE (-4250 2100);
FORCEADD Q_RES..2
(-4575 7100);
FORCEPROP 1 LAST LOCATION R8220
J 0
(-4530 7225);
DISPLAY 0.489362 (-4530 7225);
PAINT SKYBLUE (-4530 7225);
FORCEPROP 0 LAST $SEC 1
J 0
(-4525 7250);
DISPLAY 0.680851 (-4525 7250);
PAINT MONO (-4525 7250);
DISPLAY INVISIBLE (-4525 7250);
FORCEPROP 0 LAST CDS_SEC 1
J 0
(-4525 7250);
DISPLAY 1.021277 (-4525 7250);
DISPLAY INVISIBLE (-4525 7250);
FORCEPROP 1 LASTPIN (-4575 7200) $PN 1
J 0
(-4570 7162);
DISPLAY 0.489362 (-4570 7162);
PAINT MONO (-4570 7162);
FORCEPROP 1 LASTPIN (-4575 7000) $PN 2
J 0
(-4570 7010);
DISPLAY 0.489362 (-4570 7010);
PAINT MONO (-4570 7010);
FORCEPROP 1 LAST VALUE 1K
J 0
(-4545 7125);
DISPLAY 0.489362 (-4545 7125);
PAINT SKYBLUE (-4545 7125);
FORCEPROP 1 LAST WATTAGE 1/16W
J 0
(-4550 7025);
DISPLAY 0.489362 (-4550 7025);
PAINT SKYBLUE (-4550 7025);
FORCEPROP 1 LAST MATERIAL EMPTY
J 0
(-4550 6975);
DISPLAY 0.489362 (-4550 6975);
PAINT RED (-4550 6975);
FORCEPROP 1 LAST PACK_TYPE 0402LF
J 0
(-4550 6925);
DISPLAY 0.489362 (-4550 6925);
PAINT SKYBLUE (-4550 6925);
FORCEPROP 1 LAST TOLERANCE 1%
J 0
(-4545 7075);
DISPLAY 0.489362 (-4545 7075);
PAINT SKYBLUE (-4545 7075);
FORCEPROP 2 LAST CDS_LIB pure_quanta
J 0
(-4575 7100);
DISPLAY INVISIBLE (-4575 7100);
FORCEPROP 1 LAST PATH I40
J 0
(-4525 7275);
DISPLAY 0.978723 (-4525 7275);
PAINT WHITE (-4525 7275);
DISPLAY INVISIBLE (-4525 7275);
FORCEPROP 1 LAST PART_NUMBER CS21002FB06
J 0
(-4550 6925);
DISPLAY 0.489362 (-4550 6925);
PAINT SKYBLUE (-4550 6925);
DISPLAY INVISIBLE (-4550 6925);
FORCEADD Q_RES..2
(-4400 7100);
FORCEPROP 1 LAST LOCATION R8222
J 0
(-4355 7225);
DISPLAY 0.489362 (-4355 7225);
PAINT SKYBLUE (-4355 7225);
FORCEPROP 0 LAST $SEC 1
J 0
(-4350 7250);
DISPLAY 0.680851 (-4350 7250);
PAINT MONO (-4350 7250);
DISPLAY INVISIBLE (-4350 7250);
FORCEPROP 0 LAST CDS_SEC 1
J 0
(-4350 7250);
DISPLAY 1.021277 (-4350 7250);
DISPLAY INVISIBLE (-4350 7250);
FORCEPROP 1 LASTPIN (-4400 7200) $PN 1
J 0
(-4395 7162);
DISPLAY 0.489362 (-4395 7162);
PAINT MONO (-4395 7162);
FORCEPROP 1 LASTPIN (-4400 7000) $PN 2
J 0
(-4395 7010);
DISPLAY 0.489362 (-4395 7010);
PAINT MONO (-4395 7010);
FORCEPROP 1 LAST MATERIAL EMPTY
J 0
(-4375 6975);
DISPLAY 0.489362 (-4375 6975);
PAINT RED (-4375 6975);
FORCEPROP 1 LAST WATTAGE 1/16W
J 0
(-4375 7025);
DISPLAY 0.489362 (-4375 7025);
PAINT SKYBLUE (-4375 7025);
FORCEPROP 1 LAST TOLERANCE 1%
J 0
(-4370 7075);
DISPLAY 0.489362 (-4370 7075);
PAINT SKYBLUE (-4370 7075);
FORCEPROP 1 LAST PACK_TYPE 0402LF
J 0
(-4375 6925);
DISPLAY 0.489362 (-4375 6925);
PAINT SKYBLUE (-4375 6925);
FORCEPROP 1 LAST VALUE 1K
J 0
(-4370 7125);
DISPLAY 0.489362 (-4370 7125);
PAINT SKYBLUE (-4370 7125);
FORCEPROP 2 LAST CDS_LIB pure_quanta
J 0
(-4400 7100);
DISPLAY INVISIBLE (-4400 7100);
FORCEPROP 1 LAST PATH I41
J 0
(-4350 7275);
DISPLAY 0.978723 (-4350 7275);
PAINT WHITE (-4350 7275);
DISPLAY INVISIBLE (-4350 7275);
FORCEPROP 1 LAST PART_NUMBER CS21002FB06
J 0
(-4375 6925);
DISPLAY 0.489362 (-4375 6925);
PAINT SKYBLUE (-4375 6925);
DISPLAY INVISIBLE (-4375 6925);
FORCEADD Q_RES..2
(-4200 7100);
FORCEPROP 1 LAST LOCATION R8225
J 0
(-4155 7225);
DISPLAY 0.489362 (-4155 7225);
PAINT SKYBLUE (-4155 7225);
FORCEPROP 0 LAST $SEC 1
J 0
(-4150 7250);
DISPLAY 0.680851 (-4150 7250);
PAINT MONO (-4150 7250);
DISPLAY INVISIBLE (-4150 7250);
FORCEPROP 0 LAST CDS_SEC 1
J 0
(-4150 7250);
DISPLAY 1.021277 (-4150 7250);
DISPLAY INVISIBLE (-4150 7250);
FORCEPROP 1 LASTPIN (-4200 7200) $PN 1
J 0
(-4195 7162);
DISPLAY 0.489362 (-4195 7162);
PAINT MONO (-4195 7162);
FORCEPROP 1 LASTPIN (-4200 7000) $PN 2
J 0
(-4195 7010);
DISPLAY 0.489362 (-4195 7010);
PAINT MONO (-4195 7010);
FORCEPROP 1 LAST PACK_TYPE 0402LF
J 0
(-4175 6875);
DISPLAY 0.489362 (-4175 6875);
PAINT SKYBLUE (-4175 6875);
FORCEPROP 1 LAST TOLERANCE 1%
J 0
(-4170 7075);
DISPLAY 0.489362 (-4170 7075);
PAINT SKYBLUE (-4170 7075);
FORCEPROP 1 LAST MATERIAL EMPTY
J 0
(-4175 6975);
DISPLAY 0.489362 (-4175 6975);
PAINT RED (-4175 6975);
FORCEPROP 1 LAST VALUE 1K
J 0
(-4170 7125);
DISPLAY 0.489362 (-4170 7125);
PAINT SKYBLUE (-4170 7125);
FORCEPROP 1 LAST WATTAGE 1/16W
J 0
(-4175 7025);
DISPLAY 0.489362 (-4175 7025);
PAINT SKYBLUE (-4175 7025);
FORCEPROP 2 LAST CDS_LIB pure_quanta
J 0
(-4200 7100);
DISPLAY INVISIBLE (-4200 7100);
FORCEPROP 1 LAST PATH I42
J 0
(-4150 7275);
DISPLAY 0.978723 (-4150 7275);
PAINT WHITE (-4150 7275);
DISPLAY INVISIBLE (-4150 7275);
FORCEPROP 1 LAST PART_NUMBER CS21002FB06
J 0
(-4175 6925);
DISPLAY 0.489362 (-4175 6925);
PAINT SKYBLUE (-4175 6925);
DISPLAY INVISIBLE (-4175 6925);
FORCEADD OFFPAGE..5
(-3650 7225);
FORCEPROP 2 LAST $XR0 81 
J 0
(-3904 7225);
DISPLAY 0.638298 (-3904 7225);
PAINT MONO (-3904 7225);
FORCEPROP 2 LAST CDS_LIB standard
J 0
(-3650 7225);
DISPLAY INVISIBLE (-3650 7225);
FORCEPROP 1 LAST OFFPAGE TRUE
J 0
(-3325 7100);
DISPLAY 0.872340 (-3325 7100);
PAINT GREEN (-3325 7100);
DISPLAY INVISIBLE (-3325 7100);
FORCEPROP 1 LAST COMMENT_BODY TRUE
J 0
(-3550 7150);
DISPLAY 0.872340 (-3550 7150);
PAINT GREEN (-3550 7150);
DISPLAY INVISIBLE (-3550 7150);
FORCEPROP 2 LAST PATH I43
J 0
(-3900 7275);
DISPLAY 0.680851 (-3900 7275);
DISPLAY INVISIBLE (-3900 7275);
FORCEADD OFFPAGE..1
(-3650 7075);
FORCEPROP 2 LAST $XR0 82 
J 0
(-3901 7075);
DISPLAY 0.638298 (-3901 7075);
PAINT MONO (-3901 7075);
FORCEPROP 2 LAST CDS_LIB standard
J 0
(-3650 7075);
DISPLAY INVISIBLE (-3650 7075);
FORCEPROP 1 LAST OFFPAGE TRUE
J 0
(-3325 6950);
DISPLAY 0.872340 (-3325 6950);
PAINT GREEN (-3325 6950);
DISPLAY INVISIBLE (-3325 6950);
FORCEPROP 1 LAST COMMENT_BODY TRUE
J 0
(-3525 6975);
DISPLAY 0.872340 (-3525 6975);
PAINT GREEN (-3525 6975);
DISPLAY INVISIBLE (-3525 6975);
FORCEPROP 2 LAST PATH I44
J 0
(-3850 7125);
DISPLAY 0.680851 (-3850 7125);
DISPLAY INVISIBLE (-3850 7125);
FORCEADD VCC_CORE..1
(-3300 7475);
FORCEPROP 3 LASTPIN (-3300 7425) SIG_NAME P3V3_AUX\g
J 0
(-3290 7435);
DISPLAY 0.659574 (-3290 7435);
PAINT MONO (-3290 7435);
DISPLAY INVISIBLE (-3290 7435);
FORCEPROP 1 LAST HDL_POWER P3V3_AUX
J 1
(-3300 7525);
DISPLAY 0.489362 (-3300 7525);
PAINT GREEN (-3300 7525);
FORCEPROP 2 LAST CDS_LIB pure_quanta_power
J 0
(-3300 7475);
DISPLAY INVISIBLE (-3300 7475);
FORCEPROP 1 LAST PATH I45
J 0
(-3250 7500);
DISPLAY 0.872340 (-3250 7500);
PAINT AQUA (-3250 7500);
DISPLAY INVISIBLE (-3250 7500);
FORCEADD UNIVERSAL_GND..1
(-2600 1400);
FORCEPROP 3 LASTPIN (-2600 1450) SIG_NAME GND\g
J 0
(-2590 1460);
DISPLAY 0.659574 (-2590 1460);
PAINT MONO (-2590 1460);
DISPLAY INVISIBLE (-2590 1460);
FORCEPROP 2 LAST CDS_LIB pure_quanta_power
J 0
(-2600 1400);
PAINT MONO (-2600 1400);
DISPLAY INVISIBLE (-2600 1400);
FORCEPROP 1 LAST HDL_POWER GND
J 1
(-2575 1325);
DISPLAY 0.872340 (-2575 1325);
PAINT GREEN (-2575 1325);
DISPLAY INVISIBLE (-2575 1325);
FORCEPROP 1 LAST PATH I46
J 0
(-2525 1400);
DISPLAY 0.872340 (-2525 1400);
PAINT AQUA (-2525 1400);
DISPLAY INVISIBLE (-2525 1400);
FORCEADD Q_CAP..1
(-2600 1725);
FORCEPROP 1 LAST LOCATION PC357
J 0
(-2550 1825);
DISPLAY 0.489362 (-2550 1825);
PAINT SKYBLUE (-2550 1825);
FORCEPROP 0 LAST $SEC 1
J 0
(-2550 1900);
DISPLAY 0.680851 (-2550 1900);
PAINT MONO (-2550 1900);
DISPLAY INVISIBLE (-2550 1900);
FORCEPROP 0 LAST CDS_SEC 1
J 0
(-2550 1900);
DISPLAY 1.021277 (-2550 1900);
DISPLAY INVISIBLE (-2550 1900);
FORCEPROP 1 LASTPIN (-2600 1825) $PN 1
J 0
(-2590 1805);
DISPLAY 0.489362 (-2590 1805);
PAINT MONO (-2590 1805);
FORCEPROP 1 LASTPIN (-2600 1625) $PN 2
J 0
(-2590 1605);
DISPLAY 0.489362 (-2590 1605);
PAINT MONO (-2590 1605);
FORCEPROP 1 LAST VALUE 0.1UF
J 0
(-2550 1800);
DISPLAY 0.489362 (-2550 1800);
PAINT SKYBLUE (-2550 1800);
FORCEPROP 1 LAST PACK_TYPE 0402
J 0
(-2550 1600);
DISPLAY 0.489362 (-2550 1600);
PAINT SKYBLUE (-2550 1600);
FORCEPROP 1 LAST MATERIAL X7R
J 0
(-2550 1650);
DISPLAY 0.489362 (-2550 1650);
PAINT SKYBLUE (-2550 1650);
FORCEPROP 1 LAST TOLERANCE 10%
J 0
(-2550 1700);
DISPLAY 0.489362 (-2550 1700);
PAINT SKYBLUE (-2550 1700);
FORCEPROP 1 LAST VOLTAGE 25V
J 0
(-2550 1750);
DISPLAY 0.489362 (-2550 1750);
PAINT SKYBLUE (-2550 1750);
FORCEPROP 2 LAST CDS_LIB pure_quanta
J 0
(-2600 1725);
DISPLAY INVISIBLE (-2600 1725);
FORCEPROP 1 LAST PATH I47
J 0
(-2550 1875);
DISPLAY 0.978723 (-2550 1875);
PAINT WHITE (-2550 1875);
DISPLAY INVISIBLE (-2550 1875);
FORCEPROP 1 LAST PART_NUMBER CH4104K1B00
J 0
(-2550 1550);
DISPLAY 0.489362 (-2550 1550);
PAINT SKYBLUE (-2550 1550);
DISPLAY INVISIBLE (-2550 1550);
FORCEADD VCC_CORE..1
(-2325 1775);
FORCEPROP 3 LASTPIN (-2325 1725) SIG_NAME P12V_AUX\g
J 0
(-2315 1735);
DISPLAY 0.659574 (-2315 1735);
PAINT MONO (-2315 1735);
DISPLAY INVISIBLE (-2315 1735);
FORCEPROP 1 LAST HDL_POWER P12V_AUX
J 1
(-2325 1825);
DISPLAY 0.489362 (-2325 1825);
PAINT GREEN (-2325 1825);
FORCEPROP 2 LAST CDS_LIB pure_quanta_power
J 0
(-2325 1775);
DISPLAY INVISIBLE (-2325 1775);
FORCEPROP 1 LAST PATH I48
J 0
(-2275 1800);
DISPLAY 0.872340 (-2275 1800);
PAINT AQUA (-2275 1800);
DISPLAY INVISIBLE (-2275 1800);
FORCEADD Q_RES..1
(-2075 1700);
FORCEPROP 1 LAST LOCATION PR251
J 0
(-2125 1750);
DISPLAY 0.489362 (-2125 1750);
PAINT SKYBLUE (-2125 1750);
FORCEPROP 0 LAST $SEC 1
J 0
(-2125 1800);
DISPLAY 0.680851 (-2125 1800);
PAINT MONO (-2125 1800);
DISPLAY INVISIBLE (-2125 1800);
FORCEPROP 0 LAST CDS_SEC 1
J 0
(-2125 1800);
DISPLAY 1.021277 (-2125 1800);
DISPLAY INVISIBLE (-2125 1800);
FORCEPROP 1 LASTPIN (-2175 1700) $PN 1
J 0
(-2163 1712);
DISPLAY 0.489362 (-2163 1712);
PAINT MONO (-2163 1712);
FORCEPROP 1 LASTPIN (-1975 1700) $PN 2
J 0
(-2013 1712);
DISPLAY 0.489362 (-2013 1712);
PAINT MONO (-2013 1712);
FORCEPROP 1 LAST WATTAGE 1/16W
J 2
(-1900 1600);
DISPLAY 0.489362 (-1900 1600);
PAINT SKYBLUE (-1900 1600);
FORCEPROP 1 LAST MATERIAL CHIP
J 0
(-2000 1650);
DISPLAY 0.489362 (-2000 1650);
PAINT SKYBLUE (-2000 1650);
FORCEPROP 1 LAST PACK_TYPE 0402LF
J 0
(-1975 1725);
DISPLAY 0.489362 (-1975 1725);
PAINT SKYBLUE (-1975 1725);
FORCEPROP 1 LAST TOLERANCE 5%
J 0
(-2225 1725);
DISPLAY 0.489362 (-2225 1725);
PAINT SKYBLUE (-2225 1725);
FORCEPROP 1 LAST VALUE 0
J 2
(-2275 1725);
DISPLAY 0.489362 (-2275 1725);
PAINT SKYBLUE (-2275 1725);
FORCEPROP 2 LAST CDS_LIB pure_quanta
J 0
(-2075 1700);
DISPLAY INVISIBLE (-2075 1700);
FORCEPROP 1 LAST PATH I49
J 0
(-2125 1850);
DISPLAY 0.978723 (-2125 1850);
PAINT WHITE (-2125 1850);
DISPLAY INVISIBLE (-2125 1850);
FORCEPROP 1 LAST PART_NUMBER CS00002JB13
J 0
(-2375 1650);
DISPLAY 0.489362 (-2375 1650);
PAINT SKYBLUE (-2375 1650);
DISPLAY INVISIBLE (-2375 1650);
FORCEADD OFFPAGE..5
(-3925 2025);
FORCEPROP 2 LAST $XR0 81 
J 0
(-4149 2025);
DISPLAY 0.638298 (-4149 2025);
PAINT MONO (-4149 2025);
FORCEPROP 2 LAST CDS_LIB standard
J 0
(-3925 2025);
DISPLAY INVISIBLE (-3925 2025);
FORCEPROP 1 LAST OFFPAGE TRUE
J 0
(-3600 1900);
DISPLAY 0.872340 (-3600 1900);
PAINT GREEN (-3600 1900);
DISPLAY INVISIBLE (-3600 1900);
FORCEPROP 1 LAST COMMENT_BODY TRUE
J 0
(-3825 1950);
DISPLAY 0.872340 (-3825 1950);
PAINT GREEN (-3825 1950);
DISPLAY INVISIBLE (-3825 1950);
FORCEPROP 2 LAST PATH I5
J 0
(-4125 2075);
DISPLAY 0.680851 (-4125 2075);
DISPLAY INVISIBLE (-4125 2075);
FORCEADD Q_RES..1
(-2775 1975);
FORCEPROP 1 LAST LOCATION R8243
J 0
(-3000 1975);
DISPLAY 0.489362 (-3000 1975);
PAINT SKYBLUE (-3000 1975);
FORCEPROP 0 LAST $SEC 1
J 0
(-2825 2075);
DISPLAY 0.680851 (-2825 2075);
PAINT MONO (-2825 2075);
DISPLAY INVISIBLE (-2825 2075);
FORCEPROP 0 LAST CDS_SEC 1
J 0
(-2825 2075);
DISPLAY 1.021277 (-2825 2075);
DISPLAY INVISIBLE (-2825 2075);
FORCEPROP 1 LASTPIN (-2875 1975) $PN 1
J 0
(-2863 1987);
DISPLAY 0.489362 (-2863 1987);
PAINT MONO (-2863 1987);
FORCEPROP 1 LASTPIN (-2675 1975) $PN 2
J 0
(-2713 1987);
DISPLAY 0.489362 (-2713 1987);
PAINT MONO (-2713 1987);
FORCEPROP 1 LAST VALUE 33
J 2
(-2625 1975);
DISPLAY 0.489362 (-2625 1975);
PAINT SKYBLUE (-2625 1975);
FORCEPROP 1 LAST PACK_TYPE 0402LF
J 0
(-2525 1975);
DISPLAY 0.489362 (-2525 1975);
PAINT SKYBLUE (-2525 1975);
FORCEPROP 1 LAST TOLERANCE 5%
J 0
(-2600 1975);
DISPLAY 0.489362 (-2600 1975);
PAINT SKYBLUE (-2600 1975);
FORCEPROP 1 LAST WATTAGE 1/16W
J 2
(-2400 2075);
DISPLAY 0.489362 (-2400 2075);
PAINT SKYBLUE (-2400 2075);
FORCEPROP 1 LAST MATERIAL CHIP
J 0
(-2650 2075);
DISPLAY 0.489362 (-2650 2075);
PAINT SKYBLUE (-2650 2075);
FORCEPROP 2 LAST CDS_LIB pure_quanta
J 0
(-2775 1975);
DISPLAY INVISIBLE (-2775 1975);
FORCEPROP 1 LAST PATH I50
J 0
(-2825 2125);
DISPLAY 0.978723 (-2825 2125);
PAINT WHITE (-2825 2125);
DISPLAY INVISIBLE (-2825 2125);
FORCEPROP 1 LAST PART_NUMBER CS03302JB10
J 0
(-2650 2025);
DISPLAY 0.489362 (-2650 2025);
PAINT SKYBLUE (-2650 2025);
DISPLAY INVISIBLE (-2650 2025);
FORCEADD Q_RES..1
(-2775 2125);
FORCEPROP 1 LAST LOCATION R8242
J 0
(-3000 2125);
DISPLAY 0.489362 (-3000 2125);
PAINT SKYBLUE (-3000 2125);
FORCEPROP 0 LAST $SEC 1
J 0
(-2825 2225);
DISPLAY 0.680851 (-2825 2225);
PAINT MONO (-2825 2225);
DISPLAY INVISIBLE (-2825 2225);
FORCEPROP 0 LAST CDS_SEC 1
J 0
(-2825 2225);
DISPLAY 1.021277 (-2825 2225);
DISPLAY INVISIBLE (-2825 2225);
FORCEPROP 1 LASTPIN (-2875 2125) $PN 1
J 0
(-2863 2137);
DISPLAY 0.489362 (-2863 2137);
PAINT MONO (-2863 2137);
FORCEPROP 1 LASTPIN (-2675 2125) $PN 2
J 0
(-2713 2137);
DISPLAY 0.489362 (-2713 2137);
PAINT MONO (-2713 2137);
FORCEPROP 1 LAST VALUE 1K
J 2
(-2600 2125);
DISPLAY 0.489362 (-2600 2125);
PAINT SKYBLUE (-2600 2125);
FORCEPROP 1 LAST PACK_TYPE 0402LF
J 0
(-2475 2125);
DISPLAY 0.489362 (-2475 2125);
PAINT SKYBLUE (-2475 2125);
FORCEPROP 1 LAST TOLERANCE 1%
J 0
(-2575 2125);
DISPLAY 0.489362 (-2575 2125);
PAINT SKYBLUE (-2575 2125);
FORCEPROP 1 LAST MATERIAL CHIP
J 0
(-2650 2225);
DISPLAY 0.489362 (-2650 2225);
PAINT SKYBLUE (-2650 2225);
FORCEPROP 1 LAST WATTAGE 1/16W
J 2
(-2400 2225);
DISPLAY 0.489362 (-2400 2225);
PAINT SKYBLUE (-2400 2225);
FORCEPROP 2 LAST CDS_LIB pure_quanta
J 0
(-2775 2125);
DISPLAY INVISIBLE (-2775 2125);
FORCEPROP 1 LAST PATH I51
J 0
(-2825 2275);
DISPLAY 0.978723 (-2825 2275);
PAINT WHITE (-2825 2275);
DISPLAY INVISIBLE (-2825 2275);
FORCEPROP 1 LAST PART_NUMBER CS21002FB06
J 0
(-2650 2175);
DISPLAY 0.489362 (-2650 2175);
PAINT SKYBLUE (-2650 2175);
DISPLAY INVISIBLE (-2650 2175);
FORCEADD Q_CAP..2
(-1975 2125);
FORCEPROP 1 LAST LOCATION C8362
J 1
(-2175 2125);
DISPLAY 0.489362 (-2175 2125);
PAINT SKYBLUE (-2175 2125);
FORCEPROP 0 LAST $SEC 1
J 0
(-2025 2225);
DISPLAY 0.680851 (-2025 2225);
PAINT MONO (-2025 2225);
DISPLAY INVISIBLE (-2025 2225);
FORCEPROP 0 LAST CDS_SEC 1
J 0
(-2025 2225);
DISPLAY 1.021277 (-2025 2225);
DISPLAY INVISIBLE (-2025 2225);
FORCEPROP 1 LASTPIN (-2075 2125) $PN 1
J 0
(-2085 2140);
DISPLAY 0.489362 (-2085 2140);
PAINT MONO (-2085 2140);
FORCEPROP 1 LASTPIN (-1875 2125) $PN 2
J 0
(-1890 2140);
DISPLAY 0.489362 (-1890 2140);
PAINT MONO (-1890 2140);
FORCEPROP 1 LAST TOLERANCE 5%
J 2
(-1325 2075);
DISPLAY 0.489362 (-1325 2075);
PAINT SKYBLUE (-1325 2075);
FORCEPROP 1 LAST PACK_TYPE 0402
J 1
(-1475 2075);
DISPLAY 0.489362 (-1475 2075);
PAINT SKYBLUE (-1475 2075);
FORCEPROP 1 LAST VOLTAGE 50V
J 0
(-1625 2125);
DISPLAY 0.489362 (-1625 2125);
PAINT SKYBLUE (-1625 2125);
FORCEPROP 1 LAST MATERIAL EMPTY
J 0
(-1500 2125);
DISPLAY 0.489362 (-1500 2125);
PAINT RED (-1500 2125);
FORCEPROP 1 LAST VALUE 1000PF
J 2
(-1650 2125);
DISPLAY 0.489362 (-1650 2125);
PAINT SKYBLUE (-1650 2125);
FORCEPROP 2 LAST CDS_LIB pure_quanta
J 0
(-1975 2125);
DISPLAY INVISIBLE (-1975 2125);
FORCEPROP 1 LAST PATH I52
J 0
(-1975 2325);
DISPLAY 0.978723 (-1975 2325);
PAINT WHITE (-1975 2325);
DISPLAY INVISIBLE (-1975 2325);
FORCEPROP 1 LAST PART_NUMBER TMP_QCH21006JB10
J 1
(-1700 2075);
DISPLAY 0.489362 (-1700 2075);
PAINT SKYBLUE (-1700 2075);
DISPLAY INVISIBLE (-1700 2075);
FORCEADD VCC_CORE..1
(-2375 2925);
FORCEPROP 3 LASTPIN (-2375 2875) SIG_NAME PVDD18_S5_P1\g
J 0
(-2365 2885);
DISPLAY 0.659574 (-2365 2885);
PAINT MONO (-2365 2885);
DISPLAY INVISIBLE (-2365 2885);
FORCEPROP 1 LAST HDL_POWER PVDD18_S5_P1
J 1
(-2375 2975);
DISPLAY 0.489362 (-2375 2975);
PAINT GREEN (-2375 2975);
FORCEPROP 2 LAST CDS_LIB pure_quanta_power
J 0
(-2375 2925);
DISPLAY INVISIBLE (-2375 2925);
FORCEPROP 1 LAST PATH I53
J 0
(-2325 2950);
DISPLAY 0.872340 (-2325 2950);
PAINT AQUA (-2325 2950);
DISPLAY INVISIBLE (-2325 2950);
FORCEADD UNIVERSAL_GND..1
(-1800 1300);
FORCEPROP 3 LASTPIN (-1800 1350) SIG_NAME GND\g
J 0
(-1790 1360);
DISPLAY 0.659574 (-1790 1360);
PAINT MONO (-1790 1360);
DISPLAY INVISIBLE (-1790 1360);
FORCEPROP 2 LAST CDS_LIB pure_quanta_power
J 0
(-1800 1300);
DISPLAY INVISIBLE (-1800 1300);
FORCEPROP 1 LAST HDL_POWER GND
J 1
(-1775 1225);
DISPLAY 0.872340 (-1775 1225);
PAINT GREEN (-1775 1225);
DISPLAY INVISIBLE (-1775 1225);
FORCEPROP 1 LAST PATH I54
J 0
(-1725 1300);
DISPLAY 0.872340 (-1725 1300);
PAINT AQUA (-1725 1300);
DISPLAY INVISIBLE (-1725 1300);
FORCEADD Q_RES..2
(-1800 1500);
FORCEPROP 1 LAST LOCATION PR603
J 0
(-1750 1625);
DISPLAY 0.489362 (-1750 1625);
PAINT SKYBLUE (-1750 1625);
FORCEPROP 0 LAST $SEC 1
J 0
(-1750 1650);
DISPLAY 0.680851 (-1750 1650);
PAINT MONO (-1750 1650);
DISPLAY INVISIBLE (-1750 1650);
FORCEPROP 0 LAST CDS_SEC 1
J 0
(-1750 1650);
DISPLAY 0.680851 (-1750 1650);
DISPLAY INVISIBLE (-1750 1650);
FORCEPROP 1 LASTPIN (-1800 1600) $PN 1
J 0
(-1795 1562);
DISPLAY 0.787234 (-1795 1562);
PAINT MONO (-1795 1562);
DISPLAY INVISIBLE (-1795 1562);
FORCEPROP 1 LASTPIN (-1800 1400) $PN 2
J 0
(-1795 1410);
DISPLAY 0.787234 (-1795 1410);
PAINT MONO (-1795 1410);
DISPLAY INVISIBLE (-1795 1410);
FORCEPROP 1 LAST WATTAGE 1/16W
J 0
(-1750 1475);
DISPLAY 0.489362 (-1750 1475);
PAINT SKYBLUE (-1750 1475);
FORCEPROP 1 LAST MATERIAL EMPTY
J 0
(-1750 1425);
DISPLAY 0.489362 (-1750 1425);
PAINT RED (-1750 1425);
FORCEPROP 1 LAST TOLERANCE 1%
J 0
(-1750 1525);
DISPLAY 0.489362 (-1750 1525);
PAINT SKYBLUE (-1750 1525);
FORCEPROP 1 LAST VALUE 4.99K
J 0
(-1750 1575);
DISPLAY 0.489362 (-1750 1575);
PAINT SKYBLUE (-1750 1575);
FORCEPROP 1 LAST PACK_TYPE 0402LF
J 0
(-1750 1325);
DISPLAY 0.489362 (-1750 1325);
PAINT SKYBLUE (-1750 1325);
FORCEPROP 2 LAST CDS_LIB pure_quanta
J 0
(-1800 1500);
DISPLAY INVISIBLE (-1800 1500);
FORCEPROP 1 LAST PATH I55
J 0
(-1750 1675);
DISPLAY 0.978723 (-1750 1675);
PAINT WHITE (-1750 1675);
DISPLAY INVISIBLE (-1750 1675);
FORCEPROP 1 LAST PART_NUMBER CS24992FB07
J 0
(-1750 1375);
DISPLAY 0.489362 (-1750 1375);
PAINT SKYBLUE (-1750 1375);
DISPLAY INVISIBLE (-1750 1375);
FORCEADD Q_CAP..1
(-1450 1525);
FORCEPROP 1 LAST LOCATION PC364
J 0
(-1400 1650);
DISPLAY 0.489362 (-1400 1650);
PAINT SKYBLUE (-1400 1650);
FORCEPROP 0 LAST $SEC 1
J 0
(-1400 1700);
DISPLAY 0.680851 (-1400 1700);
PAINT MONO (-1400 1700);
DISPLAY INVISIBLE (-1400 1700);
FORCEPROP 0 LAST CDS_SEC 1
J 0
(-1400 1700);
DISPLAY 1.021277 (-1400 1700);
DISPLAY INVISIBLE (-1400 1700);
FORCEPROP 1 LASTPIN (-1450 1625) $PN 1
J 0
(-1440 1605);
DISPLAY 0.489362 (-1440 1605);
PAINT MONO (-1440 1605);
FORCEPROP 1 LASTPIN (-1450 1425) $PN 2
J 0
(-1440 1405);
DISPLAY 0.489362 (-1440 1405);
PAINT MONO (-1440 1405);
FORCEPROP 1 LAST PACK_TYPE 0402
J 0
(-1400 1400);
DISPLAY 0.489362 (-1400 1400);
PAINT SKYBLUE (-1400 1400);
FORCEPROP 1 LAST VOLTAGE 25V
J 0
(-1400 1550);
DISPLAY 0.489362 (-1400 1550);
PAINT SKYBLUE (-1400 1550);
FORCEPROP 1 LAST VALUE 0.1UF
J 0
(-1400 1600);
DISPLAY 0.489362 (-1400 1600);
PAINT SKYBLUE (-1400 1600);
FORCEPROP 1 LAST TOLERANCE 10%
J 0
(-1400 1500);
DISPLAY 0.489362 (-1400 1500);
PAINT SKYBLUE (-1400 1500);
FORCEPROP 1 LAST MATERIAL X7R
J 0
(-1400 1450);
DISPLAY 0.489362 (-1400 1450);
PAINT SKYBLUE (-1400 1450);
FORCEPROP 2 LAST CDS_LIB pure_quanta
J 0
(-1450 1525);
DISPLAY INVISIBLE (-1450 1525);
FORCEPROP 1 LAST PATH I56
J 0
(-1400 1675);
DISPLAY 0.978723 (-1400 1675);
PAINT WHITE (-1400 1675);
DISPLAY INVISIBLE (-1400 1675);
FORCEPROP 1 LAST PART_NUMBER CH4104K1B00
J 0
(-1400 1350);
DISPLAY 0.489362 (-1400 1350);
PAINT SKYBLUE (-1400 1350);
DISPLAY INVISIBLE (-1400 1350);
FORCEADD UNIVERSAL_GND..1
(-1450 1300);
FORCEPROP 3 LASTPIN (-1450 1350) SIG_NAME GND\g
J 0
(-1440 1360);
DISPLAY 0.659574 (-1440 1360);
PAINT MONO (-1440 1360);
DISPLAY INVISIBLE (-1440 1360);
FORCEPROP 2 LAST CDS_LIB pure_quanta_power
J 0
(-1450 1300);
PAINT MONO (-1450 1300);
DISPLAY INVISIBLE (-1450 1300);
FORCEPROP 1 LAST HDL_POWER GND
J 1
(-1425 1225);
DISPLAY 0.872340 (-1425 1225);
PAINT GREEN (-1425 1225);
DISPLAY INVISIBLE (-1425 1225);
FORCEPROP 1 LAST PATH I57
J 0
(-1375 1300);
DISPLAY 0.872340 (-1375 1300);
PAINT AQUA (-1375 1300);
DISPLAY INVISIBLE (-1375 1300);
FORCEADD UNIVERSAL_GND..1
(-1250 1550);
FORCEPROP 3 LASTPIN (-1250 1600) SIG_NAME GND\g
J 0
(-1240 1610);
DISPLAY 0.659574 (-1240 1610);
PAINT MONO (-1240 1610);
DISPLAY INVISIBLE (-1240 1610);
FORCEPROP 2 LAST CDS_LIB pure_quanta_power
J 0
(-1250 1550);
PAINT MONO (-1250 1550);
DISPLAY INVISIBLE (-1250 1550);
FORCEPROP 1 LAST HDL_POWER GND
J 1
(-1225 1475);
DISPLAY 0.872340 (-1225 1475);
PAINT GREEN (-1225 1475);
DISPLAY INVISIBLE (-1225 1475);
FORCEPROP 1 LAST PATH I58
J 0
(-1175 1550);
DISPLAY 0.872340 (-1175 1550);
PAINT AQUA (-1175 1550);
DISPLAY INVISIBLE (-1175 1550);
FORCEADD UNIVERSAL_GND..1
R 1
(-1425 2850);
FORCEPROP 3 LASTPIN (-1475 2850) SIG_NAME GND\g
J 0
(-1465 2860);
DISPLAY 0.659574 (-1465 2860);
PAINT MONO (-1465 2860);
DISPLAY INVISIBLE (-1465 2860);
FORCEPROP 2 LAST CDS_LIB pure_quanta_power
J 0
(-1425 2850);
DISPLAY INVISIBLE (-1425 2850);
FORCEPROP 1 LAST HDL_POWER GND
R 1
J 1
(-1350 2875);
DISPLAY 0.872340 (-1350 2875);
PAINT GREEN (-1350 2875);
DISPLAY INVISIBLE (-1350 2875);
FORCEPROP 1 LAST PATH I59
R 1
J 0
(-1425 2925);
DISPLAY 0.872340 (-1425 2925);
PAINT AQUA (-1425 2925);
DISPLAY INVISIBLE (-1425 2925);
FORCEADD MOSFET_N..1
(-4050 2675);
FORCEPROP 1 LAST LOCATION PQ16
J 0
(-3925 2700);
DISPLAY 0.489362 (-3925 2700);
PAINT SKYBLUE (-3925 2700);
FORCEPROP 0 LAST $SEC 1
J 0
(-3900 2725);
DISPLAY 0.680851 (-3900 2725);
PAINT MONO (-3900 2725);
DISPLAY INVISIBLE (-3900 2725);
FORCEPROP 0 LAST CDS_SEC 1
J 0
(-3900 2725);
DISPLAY 1.021277 (-3900 2725);
DISPLAY INVISIBLE (-3900 2725);
FORCEPROP 1 LASTPIN (-4000 2775) $PN D
R 1
J 0
(-4000 2768);
DISPLAY 0.489362 (-4000 2768);
PAINT MONO (-4000 2768);
FORCEPROP 1 LASTPIN (-4150 2575) $PN G
J 2
(-4140 2578);
DISPLAY 0.489362 (-4140 2578);
PAINT MONO (-4140 2578);
FORCEPROP 1 LASTPIN (-4000 2475) $PN S
R 1
J 2
(-4000 2488);
DISPLAY 0.489362 (-4000 2488);
PAINT MONO (-4000 2488);
FORCEPROP 1 LAST VALUE BSS138K
J 0
(-3925 2650);
DISPLAY 0.489362 (-3925 2650);
PAINT SKYBLUE (-3925 2650);
FORCEPROP 1 LAST MATERIAL IC
J 0
(-3925 2550);
DISPLAY 0.489362 (-3925 2550);
PAINT SKYBLUE (-3925 2550);
FORCEPROP 2 LAST PATH I6
J 0
(-3925 2725);
DISPLAY 0.680851 (-3925 2725);
FORCEPROP 1 LAST PACK_TYPE SMLF
J 0
(-4025 2425);
DISPLAY 0.723404 (-4025 2425);
PAINT SKYBLUE (-4025 2425);
DISPLAY INVISIBLE (-4025 2425);
FORCEPROP 0 LAST MANUF_PN BSS138K
J 0
(-3875 2550);
DISPLAY 1.021277 (-3875 2550);
DISPLAY INVISIBLE (-3875 2550);
FORCEPROP 1 LAST CDS_LMAN_SYM_OUTLINE -50,50,100,-150
J 0
(-4050 2675);
DISPLAY 0.468085 (-4050 2675);
PAINT GREEN (-4050 2675);
DISPLAY INVISIBLE (-4050 2675);
FORCEPROP 2 LAST CDS_LIB pure_quanta
J 0
(-4050 2675);
DISPLAY INVISIBLE (-4050 2675);
FORCEPROP 1 LAST PART_NUMBER BAM138K0000
J 0
(-3925 2600);
DISPLAY 0.489362 (-3925 2600);
PAINT SKYBLUE (-3925 2600);
DISPLAY INVISIBLE (-3925 2600);
FORCEADD Q_CAP..2
(-1825 2850);
FORCEPROP 1 LAST LOCATION PC363
J 1
(-2150 2900);
DISPLAY 0.489362 (-2150 2900);
PAINT SKYBLUE (-2150 2900);
FORCEPROP 0 LAST $SEC 1
J 0
(-1250 2925);
DISPLAY 0.680851 (-1250 2925);
PAINT MONO (-1250 2925);
DISPLAY INVISIBLE (-1250 2925);
FORCEPROP 0 LAST CDS_SEC 1
J 0
(-1250 2925);
DISPLAY 1.021277 (-1250 2925);
DISPLAY INVISIBLE (-1250 2925);
FORCEPROP 1 LASTPIN (-1925 2850) $PN 1
J 0
(-1935 2865);
DISPLAY 0.489362 (-1935 2865);
PAINT MONO (-1935 2865);
FORCEPROP 1 LASTPIN (-1725 2850) $PN 2
J 0
(-1740 2865);
DISPLAY 0.489362 (-1740 2865);
PAINT MONO (-1740 2865);
FORCEPROP 1 LAST TOLERANCE 10%
J 2
(-1250 2900);
DISPLAY 0.489362 (-1250 2900);
PAINT SKYBLUE (-1250 2900);
FORCEPROP 1 LAST PACK_TYPE 0402
J 1
(-1400 2900);
DISPLAY 0.489362 (-1400 2900);
PAINT SKYBLUE (-1400 2900);
FORCEPROP 1 LAST MATERIAL X7R
J 0
(-1850 2900);
DISPLAY 0.489362 (-1850 2900);
PAINT SKYBLUE (-1850 2900);
FORCEPROP 1 LAST VALUE 1UF
J 2
(-2025 2900);
DISPLAY 0.489362 (-2025 2900);
PAINT SKYBLUE (-2025 2900);
FORCEPROP 1 LAST VOLTAGE 6.3V
J 0
(-1975 2900);
DISPLAY 0.489362 (-1975 2900);
PAINT SKYBLUE (-1975 2900);
FORCEPROP 2 LAST CDS_LIB pure_quanta
J 0
(-1825 2850);
DISPLAY INVISIBLE (-1825 2850);
FORCEPROP 1 LAST PATH I60
J 0
(-1825 3050);
DISPLAY 0.978723 (-1825 3050);
PAINT WHITE (-1825 3050);
DISPLAY INVISIBLE (-1825 3050);
FORCEPROP 1 LAST PART_NUMBER CH5101K1B01
J 1
(-1600 2900);
DISPLAY 0.489362 (-1600 2900);
PAINT SKYBLUE (-1600 2900);
DISPLAY INVISIBLE (-1600 2900);
FORCEADD UNIVERSAL_GND..1
R 1
(-1275 2125);
FORCEPROP 3 LASTPIN (-1325 2125) SIG_NAME GND\g
J 0
(-1315 2135);
DISPLAY 0.659574 (-1315 2135);
PAINT MONO (-1315 2135);
DISPLAY INVISIBLE (-1315 2135);
FORCEPROP 2 LAST CDS_LIB pure_quanta_power
J 0
(-1275 2125);
PAINT MONO (-1275 2125);
DISPLAY INVISIBLE (-1275 2125);
FORCEPROP 1 LAST HDL_POWER GND
R 1
J 1
(-1200 2150);
DISPLAY 0.872340 (-1200 2150);
PAINT GREEN (-1200 2150);
DISPLAY INVISIBLE (-1200 2150);
FORCEPROP 1 LAST PATH I61
R 1
J 0
(-1275 2200);
DISPLAY 0.872340 (-1275 2200);
PAINT AQUA (-1275 2200);
DISPLAY INVISIBLE (-1275 2200);
FORCEADD UNIVERSAL_GND..1
(-2900 3500);
FORCEPROP 3 LASTPIN (-2900 3550) SIG_NAME GND\g
J 0
(-2890 3560);
DISPLAY 0.659574 (-2890 3560);
PAINT MONO (-2890 3560);
DISPLAY INVISIBLE (-2890 3560);
FORCEPROP 2 LAST CDS_LIB pure_quanta_power
J 0
(-2900 3500);
DISPLAY INVISIBLE (-2900 3500);
FORCEPROP 1 LAST HDL_POWER GND
J 1
(-2875 3425);
DISPLAY 0.872340 (-2875 3425);
PAINT GREEN (-2875 3425);
DISPLAY INVISIBLE (-2875 3425);
FORCEPROP 1 LAST PATH I62
J 0
(-2825 3500);
DISPLAY 0.872340 (-2825 3500);
PAINT AQUA (-2825 3500);
DISPLAY INVISIBLE (-2825 3500);
FORCEADD VCC_CORE..1
(-2675 3650);
FORCEPROP 3 LASTPIN (-2675 3600) SIG_NAME PVDD18_S5_P1\g
J 0
(-2665 3610);
DISPLAY 0.659574 (-2665 3610);
PAINT MONO (-2665 3610);
DISPLAY INVISIBLE (-2665 3610);
FORCEPROP 1 LAST HDL_POWER PVDD18_S5_P1
J 1
(-2675 3700);
DISPLAY 0.489362 (-2675 3700);
PAINT GREEN (-2675 3700);
FORCEPROP 2 LAST CDS_LIB pure_quanta_power
J 0
(-2675 3650);
DISPLAY INVISIBLE (-2675 3650);
FORCEPROP 1 LAST PATH I63
J 0
(-2625 3675);
DISPLAY 0.872340 (-2625 3675);
PAINT AQUA (-2625 3675);
DISPLAY INVISIBLE (-2625 3675);
FORCEADD Q_RES..1
(-2200 3225);
FORCEPROP 1 LAST LOCATION R8241
J 0
(-2250 3275);
DISPLAY 0.489362 (-2250 3275);
PAINT SKYBLUE (-2250 3275);
FORCEPROP 0 LAST $SEC 1
J 0
(-2250 3300);
DISPLAY 0.680851 (-2250 3300);
PAINT MONO (-2250 3300);
DISPLAY INVISIBLE (-2250 3300);
FORCEPROP 0 LAST CDS_SEC 1
J 0
(-2250 3300);
DISPLAY 1.021277 (-2250 3300);
DISPLAY INVISIBLE (-2250 3300);
FORCEPROP 1 LASTPIN (-2300 3225) $PN 1
J 0
(-2288 3237);
DISPLAY 0.489362 (-2288 3237);
PAINT MONO (-2288 3237);
FORCEPROP 1 LASTPIN (-2100 3225) $PN 2
J 0
(-2138 3237);
DISPLAY 0.489362 (-2138 3237);
PAINT MONO (-2138 3237);
FORCEPROP 1 LAST VALUE 0
J 2
(-2200 3175);
DISPLAY 0.489362 (-2200 3175);
PAINT SKYBLUE (-2200 3175);
FORCEPROP 1 LAST WATTAGE 1/16W
J 2
(-2275 3175);
DISPLAY 0.489362 (-2275 3175);
PAINT SKYBLUE (-2275 3175);
FORCEPROP 1 LAST MATERIAL CHIP
J 0
(-2525 3175);
DISPLAY 0.489362 (-2525 3175);
PAINT SKYBLUE (-2525 3175);
FORCEPROP 1 LAST TOLERANCE 5%
J 0
(-2175 3175);
DISPLAY 0.489362 (-2175 3175);
PAINT SKYBLUE (-2175 3175);
FORCEPROP 1 LAST PACK_TYPE 0402LF
J 0
(-2100 3175);
DISPLAY 0.489362 (-2100 3175);
PAINT SKYBLUE (-2100 3175);
FORCEPROP 2 LAST CDS_LIB pure_quanta
J 0
(-2200 3225);
DISPLAY INVISIBLE (-2200 3225);
FORCEPROP 1 LAST PATH I64
J 0
(-2250 3375);
DISPLAY 0.978723 (-2250 3375);
PAINT WHITE (-2250 3375);
DISPLAY INVISIBLE (-2250 3375);
FORCEPROP 1 LAST PART_NUMBER CS00002JB13
J 0
(-2875 3175);
DISPLAY 0.489362 (-2875 3175);
PAINT SKYBLUE (-2875 3175);
DISPLAY INVISIBLE (-2875 3175);
FORCEADD Q_RES..1
(-2200 3375);
FORCEPROP 1 LAST LOCATION R240
J 0
(-2250 3425);
DISPLAY 0.489362 (-2250 3425);
PAINT SKYBLUE (-2250 3425);
FORCEPROP 0 LAST $SEC 1
J 0
(-2250 3450);
DISPLAY 0.680851 (-2250 3450);
PAINT MONO (-2250 3450);
DISPLAY INVISIBLE (-2250 3450);
FORCEPROP 0 LAST CDS_SEC 1
J 0
(-2250 3450);
DISPLAY 1.021277 (-2250 3450);
DISPLAY INVISIBLE (-2250 3450);
FORCEPROP 1 LASTPIN (-2300 3375) $PN 1
J 0
(-2288 3387);
DISPLAY 0.489362 (-2288 3387);
PAINT MONO (-2288 3387);
FORCEPROP 1 LASTPIN (-2100 3375) $PN 2
J 0
(-2138 3387);
DISPLAY 0.489362 (-2138 3387);
PAINT MONO (-2138 3387);
FORCEPROP 1 LAST VALUE 100
J 2
(-2175 3325);
DISPLAY 0.489362 (-2175 3325);
PAINT SKYBLUE (-2175 3325);
FORCEPROP 1 LAST TOLERANCE 1%
J 0
(-2150 3325);
DISPLAY 0.489362 (-2150 3325);
PAINT SKYBLUE (-2150 3325);
FORCEPROP 1 LAST PACK_TYPE 0402LF
J 0
(-2075 3325);
DISPLAY 0.489362 (-2075 3325);
PAINT SKYBLUE (-2075 3325);
FORCEPROP 1 LAST WATTAGE 1/16W
J 2
(-2275 3325);
DISPLAY 0.489362 (-2275 3325);
PAINT SKYBLUE (-2275 3325);
FORCEPROP 1 LAST MATERIAL CHIP
J 0
(-2525 3325);
DISPLAY 0.489362 (-2525 3325);
PAINT SKYBLUE (-2525 3325);
FORCEPROP 2 LAST CDS_LIB pure_quanta
J 0
(-2200 3375);
DISPLAY INVISIBLE (-2200 3375);
FORCEPROP 1 LAST PATH I65
J 0
(-2250 3525);
DISPLAY 0.978723 (-2250 3525);
PAINT WHITE (-2250 3525);
DISPLAY INVISIBLE (-2250 3525);
FORCEPROP 1 LAST PART_NUMBER CS11002FB07
J 0
(-2875 3325);
DISPLAY 0.489362 (-2875 3325);
PAINT SKYBLUE (-2875 3325);
DISPLAY INVISIBLE (-2875 3325);
FORCEADD Q_RES..1
(-2225 3525);
FORCEPROP 1 LAST LOCATION R8247
J 0
(-2600 3550);
DISPLAY 0.489362 (-2600 3550);
PAINT SKYBLUE (-2600 3550);
FORCEPROP 0 LAST $SEC 1
J 0
(-2475 3625);
DISPLAY 0.680851 (-2475 3625);
PAINT MONO (-2475 3625);
DISPLAY INVISIBLE (-2475 3625);
FORCEPROP 0 LAST CDS_SEC 1
J 0
(-2475 3625);
DISPLAY 1.021277 (-2475 3625);
DISPLAY INVISIBLE (-2475 3625);
FORCEPROP 1 LASTPIN (-2325 3525) $PN 1
J 0
(-2313 3537);
DISPLAY 0.489362 (-2313 3537);
PAINT MONO (-2313 3537);
FORCEPROP 1 LASTPIN (-2125 3525) $PN 2
J 0
(-2163 3537);
DISPLAY 0.489362 (-2163 3537);
PAINT MONO (-2163 3537);
FORCEPROP 1 LAST TOLERANCE 1%
J 0
(-2400 3550);
DISPLAY 0.489362 (-2400 3550);
PAINT SKYBLUE (-2400 3550);
FORCEPROP 1 LAST VALUE 1K
J 2
(-2425 3550);
DISPLAY 0.489362 (-2425 3550);
PAINT SKYBLUE (-2425 3550);
FORCEPROP 1 LAST MATERIAL CHIP
J 0
(-2175 3550);
DISPLAY 0.489362 (-2175 3550);
PAINT SKYBLUE (-2175 3550);
FORCEPROP 1 LAST PACK_TYPE 0402LF
J 0
(-2325 3550);
DISPLAY 0.489362 (-2325 3550);
PAINT SKYBLUE (-2325 3550);
FORCEPROP 1 LAST WATTAGE 1/16W
J 2
(-1950 3550);
DISPLAY 0.489362 (-1950 3550);
PAINT SKYBLUE (-1950 3550);
FORCEPROP 2 LAST CDS_LIB pure_quanta
J 0
(-2225 3525);
DISPLAY INVISIBLE (-2225 3525);
FORCEPROP 1 LAST PATH I66
J 0
(-2275 3675);
DISPLAY 0.978723 (-2275 3675);
PAINT WHITE (-2275 3675);
DISPLAY INVISIBLE (-2275 3675);
FORCEPROP 1 LAST PART_NUMBER CS21002FB06
J 0
(-2475 3600);
DISPLAY 0.489362 (-2475 3600);
PAINT SKYBLUE (-2475 3600);
DISPLAY INVISIBLE (-2475 3600);
FORCEADD Q_CAP..1
(-2025 3950);
FORCEPROP 1 LAST LOCATION PC361
J 0
(-1975 4075);
DISPLAY 0.489362 (-1975 4075);
PAINT SKYBLUE (-1975 4075);
FORCEPROP 0 LAST $SEC 1
J 0
(-1975 4075);
DISPLAY 0.680851 (-1975 4075);
PAINT MONO (-1975 4075);
DISPLAY INVISIBLE (-1975 4075);
FORCEPROP 0 LAST CDS_SEC 1
J 0
(-1975 4075);
DISPLAY 1.021277 (-1975 4075);
DISPLAY INVISIBLE (-1975 4075);
FORCEPROP 1 LASTPIN (-2025 4050) $PN 1
J 0
(-2015 4030);
DISPLAY 0.489362 (-2015 4030);
PAINT MONO (-2015 4030);
FORCEPROP 1 LASTPIN (-2025 3850) $PN 2
J 0
(-2015 3830);
DISPLAY 0.489362 (-2015 3830);
PAINT MONO (-2015 3830);
FORCEPROP 1 LAST VOLTAGE 50V
J 0
(-1975 3975);
DISPLAY 0.489362 (-1975 3975);
PAINT SKYBLUE (-1975 3975);
FORCEPROP 1 LAST VALUE 3300PF
J 0
(-1975 4025);
DISPLAY 0.489362 (-1975 4025);
PAINT SKYBLUE (-1975 4025);
FORCEPROP 1 LAST PACK_TYPE 0402
J 0
(-1975 3825);
DISPLAY 0.489362 (-1975 3825);
PAINT SKYBLUE (-1975 3825);
FORCEPROP 1 LAST TOLERANCE 10%
J 0
(-1975 3925);
DISPLAY 0.489362 (-1975 3925);
PAINT SKYBLUE (-1975 3925);
FORCEPROP 1 LAST MATERIAL X7R
J 0
(-1975 3875);
DISPLAY 0.489362 (-1975 3875);
PAINT SKYBLUE (-1975 3875);
FORCEPROP 2 LAST CDS_LIB pure_quanta
J 0
(-2025 3950);
DISPLAY INVISIBLE (-2025 3950);
FORCEPROP 1 LAST PATH I67
J 0
(-1975 4100);
DISPLAY 0.978723 (-1975 4100);
PAINT WHITE (-1975 4100);
DISPLAY INVISIBLE (-1975 4100);
FORCEPROP 1 LAST PART_NUMBER TMP_QCH2336K1B12
J 0
(-1975 3775);
DISPLAY 0.489362 (-1975 3775);
PAINT SKYBLUE (-1975 3775);
DISPLAY INVISIBLE (-1975 3775);
FORCEADD VCC_CORE..1
(-2875 4425);
FORCEPROP 3 LASTPIN (-2875 4375) SIG_NAME PVDDIO_P1\g
J 0
(-2865 4385);
DISPLAY 0.659574 (-2865 4385);
PAINT MONO (-2865 4385);
DISPLAY INVISIBLE (-2865 4385);
FORCEPROP 1 LAST HDL_POWER PVDDIO_P1
J 1
(-2875 4475);
DISPLAY 0.489362 (-2875 4475);
PAINT GREEN (-2875 4475);
FORCEPROP 2 LAST CDS_LIB pure_quanta_power
J 0
(-2875 4425);
DISPLAY INVISIBLE (-2875 4425);
FORCEPROP 1 LAST PATH I68
J 0
(-2825 4450);
DISPLAY 0.872340 (-2825 4450);
PAINT AQUA (-2825 4450);
DISPLAY INVISIBLE (-2825 4450);
FORCEADD Q_RES..1
(-2475 4125);
FORCEPROP 1 LAST LOCATION PR246
J 0
(-2525 4175);
DISPLAY 0.489362 (-2525 4175);
PAINT SKYBLUE (-2525 4175);
FORCEPROP 0 LAST $SEC 1
J 0
(-2525 4225);
DISPLAY 0.680851 (-2525 4225);
PAINT MONO (-2525 4225);
DISPLAY INVISIBLE (-2525 4225);
FORCEPROP 0 LAST CDS_SEC 1
J 0
(-2525 4225);
DISPLAY 1.021277 (-2525 4225);
DISPLAY INVISIBLE (-2525 4225);
FORCEPROP 1 LASTPIN (-2575 4125) $PN 1
J 0
(-2563 4137);
DISPLAY 0.489362 (-2563 4137);
PAINT MONO (-2563 4137);
FORCEPROP 1 LASTPIN (-2375 4125) $PN 2
J 0
(-2413 4137);
DISPLAY 0.489362 (-2413 4137);
PAINT MONO (-2413 4137);
FORCEPROP 1 LAST PACK_TYPE 0402LF
J 0
(-2375 4025);
DISPLAY 0.489362 (-2375 4025);
PAINT SKYBLUE (-2375 4025);
FORCEPROP 1 LAST MATERIAL CHIP
J 0
(-2350 4075);
DISPLAY 0.489362 (-2350 4075);
PAINT SKYBLUE (-2350 4075);
FORCEPROP 1 LAST WATTAGE 1/16W
J 2
(-2250 4150);
DISPLAY 0.489362 (-2250 4150);
PAINT SKYBLUE (-2250 4150);
FORCEPROP 1 LAST TOLERANCE 5%
J 0
(-2650 4150);
DISPLAY 0.489362 (-2650 4150);
PAINT SKYBLUE (-2650 4150);
FORCEPROP 1 LAST VALUE 0
J 2
(-2700 4150);
DISPLAY 0.489362 (-2700 4150);
PAINT SKYBLUE (-2700 4150);
FORCEPROP 2 LAST CDS_LIB pure_quanta
J 0
(-2475 4125);
DISPLAY INVISIBLE (-2475 4125);
FORCEPROP 1 LAST PATH I69
J 0
(-2525 4275);
DISPLAY 0.978723 (-2525 4275);
PAINT WHITE (-2525 4275);
DISPLAY INVISIBLE (-2525 4275);
FORCEPROP 1 LAST PART_NUMBER CS00002JB13
J 0
(-2875 4050);
DISPLAY 0.489362 (-2875 4050);
PAINT SKYBLUE (-2875 4050);
DISPLAY INVISIBLE (-2875 4050);
FORCEADD UNIVERSAL_GND..1
(-4000 2275);
FORCEPROP 3 LASTPIN (-4000 2325) SIG_NAME GND\g
J 0
(-3990 2335);
DISPLAY 0.659574 (-3990 2335);
PAINT MONO (-3990 2335);
DISPLAY INVISIBLE (-3990 2335);
FORCEPROP 2 LAST CDS_LIB pure_quanta_power
J 0
(-4000 2275);
DISPLAY INVISIBLE (-4000 2275);
FORCEPROP 1 LAST HDL_POWER GND
J 1
(-3975 2200);
DISPLAY 0.872340 (-3975 2200);
PAINT GREEN (-3975 2200);
DISPLAY INVISIBLE (-3975 2200);
FORCEPROP 1 LAST PATH I7
J 0
(-3925 2275);
DISPLAY 0.872340 (-3925 2275);
PAINT AQUA (-3925 2275);
DISPLAY INVISIBLE (-3925 2275);
FORCEADD UNIVERSAL_GND..1
(-2875 4600);
FORCEPROP 3 LASTPIN (-2875 4650) SIG_NAME GND\g
J 0
(-2865 4660);
DISPLAY 0.659574 (-2865 4660);
PAINT MONO (-2865 4660);
DISPLAY INVISIBLE (-2865 4660);
FORCEPROP 2 LAST CDS_LIB pure_quanta_power
J 0
(-2875 4600);
DISPLAY INVISIBLE (-2875 4600);
FORCEPROP 1 LAST HDL_POWER GND
J 1
(-2850 4525);
DISPLAY 0.872340 (-2850 4525);
PAINT GREEN (-2850 4525);
DISPLAY INVISIBLE (-2850 4525);
FORCEPROP 1 LAST PATH I70
J 0
(-2800 4600);
DISPLAY 0.872340 (-2800 4600);
PAINT AQUA (-2800 4600);
DISPLAY INVISIBLE (-2800 4600);
FORCEADD Q_RES..1
(-1550 3100);
FORCEPROP 1 LAST LOCATION R8252
J 0
(-1600 3050);
DISPLAY 0.489362 (-1600 3050);
PAINT SKYBLUE (-1600 3050);
FORCEPROP 0 LAST $SEC 1
J 0
(-1800 3200);
DISPLAY 0.680851 (-1800 3200);
PAINT MONO (-1800 3200);
DISPLAY INVISIBLE (-1800 3200);
FORCEPROP 0 LAST CDS_SEC 1
J 0
(-1800 3200);
DISPLAY 1.021277 (-1800 3200);
DISPLAY INVISIBLE (-1800 3200);
FORCEPROP 1 LASTPIN (-1650 3100) $PN 1
J 0
(-1638 3112);
DISPLAY 0.489362 (-1638 3112);
PAINT MONO (-1638 3112);
FORCEPROP 1 LASTPIN (-1450 3100) $PN 2
J 0
(-1488 3112);
DISPLAY 0.489362 (-1488 3112);
PAINT MONO (-1488 3112);
FORCEPROP 1 LAST WATTAGE 1/16W
J 2
(-1275 3125);
DISPLAY 0.489362 (-1275 3125);
PAINT SKYBLUE (-1275 3125);
FORCEPROP 1 LAST VALUE 1K
J 2
(-1750 3125);
DISPLAY 0.489362 (-1750 3125);
PAINT SKYBLUE (-1750 3125);
FORCEPROP 1 LAST MATERIAL CHIP
J 0
(-1500 3150);
DISPLAY 0.489362 (-1500 3150);
PAINT SKYBLUE (-1500 3150);
FORCEPROP 1 LAST TOLERANCE 1%
J 0
(-1725 3125);
DISPLAY 0.489362 (-1725 3125);
PAINT SKYBLUE (-1725 3125);
FORCEPROP 1 LAST PACK_TYPE 0402LF
J 0
(-1650 3150);
DISPLAY 0.489362 (-1650 3150);
PAINT SKYBLUE (-1650 3150);
FORCEPROP 2 LAST CDS_LIB pure_quanta
J 0
(-1550 3100);
DISPLAY INVISIBLE (-1550 3100);
FORCEPROP 1 LAST PATH I71
J 0
(-1600 3250);
DISPLAY 0.978723 (-1600 3250);
PAINT WHITE (-1600 3250);
DISPLAY INVISIBLE (-1600 3250);
FORCEPROP 1 LAST PART_NUMBER CS21002FB06
J 0
(-1800 3175);
DISPLAY 0.489362 (-1800 3175);
PAINT SKYBLUE (-1800 3175);
DISPLAY INVISIBLE (-1800 3175);
FORCEADD UNIVERSAL_GND..1
(850 1600);
FORCEPROP 3 LASTPIN (850 1650) SIG_NAME GND\g
J 0
(860 1660);
DISPLAY 0.659574 (860 1660);
PAINT MONO (860 1660);
DISPLAY INVISIBLE (860 1660);
FORCEPROP 2 LAST CDS_LIB pure_quanta_power
J 0
(850 1600);
PAINT MONO (850 1600);
DISPLAY INVISIBLE (850 1600);
FORCEPROP 1 LAST HDL_POWER GND
J 1
(875 1525);
DISPLAY 0.872340 (875 1525);
PAINT GREEN (875 1525);
DISPLAY INVISIBLE (875 1525);
FORCEPROP 1 LAST PATH I72
J 0
(925 1600);
DISPLAY 0.872340 (925 1600);
PAINT AQUA (925 1600);
DISPLAY INVISIBLE (925 1600);
FORCEADD Q_CAP..1
(850 1850);
FORCEPROP 1 LAST LOCATION PC368
J 0
(900 1950);
DISPLAY 0.489362 (900 1950);
PAINT SKYBLUE (900 1950);
FORCEPROP 0 LAST $SEC 1
J 0
(900 2000);
DISPLAY 0.680851 (900 2000);
PAINT MONO (900 2000);
DISPLAY INVISIBLE (900 2000);
FORCEPROP 0 LAST CDS_SEC 1
J 0
(900 2000);
DISPLAY 1.021277 (900 2000);
DISPLAY INVISIBLE (900 2000);
FORCEPROP 1 LASTPIN (850 1950) $PN 1
J 0
(860 1930);
DISPLAY 0.489362 (860 1930);
PAINT MONO (860 1930);
FORCEPROP 1 LASTPIN (850 1750) $PN 2
J 0
(860 1730);
DISPLAY 0.489362 (860 1730);
PAINT MONO (860 1730);
FORCEPROP 1 LAST PACK_TYPE 0402
J 0
(900 1700);
DISPLAY 0.489362 (900 1700);
PAINT SKYBLUE (900 1700);
FORCEPROP 1 LAST VALUE 470PF
J 0
(900 1900);
DISPLAY 0.489362 (900 1900);
PAINT SKYBLUE (900 1900);
FORCEPROP 1 LAST TOLERANCE 10%
J 0
(900 1800);
DISPLAY 0.489362 (900 1800);
PAINT SKYBLUE (900 1800);
FORCEPROP 1 LAST MATERIAL X7R
J 0
(900 1750);
DISPLAY 0.489362 (900 1750);
PAINT SKYBLUE (900 1750);
FORCEPROP 1 LAST VOLTAGE 50V
J 0
(900 1850);
DISPLAY 0.489362 (900 1850);
PAINT SKYBLUE (900 1850);
FORCEPROP 2 LAST CDS_LIB pure_quanta
J 0
(850 1850);
DISPLAY INVISIBLE (850 1850);
FORCEPROP 1 LAST PATH I73
J 0
(900 2000);
DISPLAY 0.978723 (900 2000);
PAINT WHITE (900 2000);
DISPLAY INVISIBLE (900 2000);
FORCEPROP 1 LAST PART_NUMBER TMP_QCH14706KB18
J 0
(900 1625);
DISPLAY 0.489362 (900 1625);
PAINT SKYBLUE (900 1625);
DISPLAY INVISIBLE (900 1625);
FORCEADD UNIVERSAL_GND..1
(850 2175);
FORCEPROP 3 LASTPIN (850 2225) SIG_NAME GND\g
J 0
(860 2235);
DISPLAY 0.659574 (860 2235);
PAINT MONO (860 2235);
DISPLAY INVISIBLE (860 2235);
FORCEPROP 2 LAST CDS_LIB pure_quanta_power
J 0
(850 2175);
DISPLAY INVISIBLE (850 2175);
FORCEPROP 1 LAST HDL_POWER GND
J 1
(875 2100);
DISPLAY 0.872340 (875 2100);
PAINT GREEN (875 2100);
DISPLAY INVISIBLE (875 2100);
FORCEPROP 1 LAST PATH I74
J 0
(925 2175);
DISPLAY 0.872340 (925 2175);
PAINT AQUA (925 2175);
DISPLAY INVISIBLE (925 2175);
FORCEADD Q_CAP..1
(850 2425);
FORCEPROP 1 LAST LOCATION PC367
J 0
(900 2525);
DISPLAY 0.489362 (900 2525);
PAINT SKYBLUE (900 2525);
FORCEPROP 0 LAST $SEC 1
J 0
(900 2550);
DISPLAY 0.680851 (900 2550);
PAINT MONO (900 2550);
DISPLAY INVISIBLE (900 2550);
FORCEPROP 0 LAST CDS_SEC 1
J 0
(900 2550);
DISPLAY 1.021277 (900 2550);
DISPLAY INVISIBLE (900 2550);
FORCEPROP 1 LASTPIN (850 2525) $PN 1
J 0
(860 2505);
DISPLAY 0.489362 (860 2505);
PAINT MONO (860 2505);
FORCEPROP 1 LASTPIN (850 2325) $PN 2
J 0
(860 2305);
DISPLAY 0.489362 (860 2305);
PAINT MONO (860 2305);
FORCEPROP 1 LAST PACK_TYPE 0402
J 0
(900 2275);
DISPLAY 0.489362 (900 2275);
PAINT SKYBLUE (900 2275);
FORCEPROP 1 LAST VOLTAGE 50V
J 0
(900 2425);
DISPLAY 0.489362 (900 2425);
PAINT SKYBLUE (900 2425);
FORCEPROP 1 LAST VALUE 470PF
J 0
(900 2475);
DISPLAY 0.489362 (900 2475);
PAINT SKYBLUE (900 2475);
FORCEPROP 1 LAST TOLERANCE 10%
J 0
(900 2375);
DISPLAY 0.489362 (900 2375);
PAINT SKYBLUE (900 2375);
FORCEPROP 1 LAST MATERIAL X7R
J 0
(900 2325);
DISPLAY 0.489362 (900 2325);
PAINT SKYBLUE (900 2325);
FORCEPROP 2 LAST CDS_LIB pure_quanta
J 0
(850 2425);
DISPLAY INVISIBLE (850 2425);
FORCEPROP 1 LAST PATH I75
J 0
(900 2575);
DISPLAY 0.978723 (900 2575);
PAINT WHITE (900 2575);
DISPLAY INVISIBLE (900 2575);
FORCEPROP 1 LAST PART_NUMBER TMP_QCH14706KB18
J 0
(900 2200);
DISPLAY 0.489362 (900 2200);
PAINT SKYBLUE (900 2200);
DISPLAY INVISIBLE (900 2200);
FORCEADD Q_RES..1
(925 4325);
FORCEPROP 1 LAST LOCATION PR533
J 0
(875 4375);
DISPLAY 0.489362 (875 4375);
PAINT SKYBLUE (875 4375);
FORCEPROP 0 LAST $SEC 1
J 0
(875 4400);
DISPLAY 0.680851 (875 4400);
PAINT MONO (875 4400);
DISPLAY INVISIBLE (875 4400);
FORCEPROP 0 LAST CDS_SEC 1
J 0
(875 4400);
DISPLAY 0.680851 (875 4400);
DISPLAY INVISIBLE (875 4400);
FORCEPROP 1 LASTPIN (825 4325) $PN 1
J 0
(837 4337);
DISPLAY 0.787234 (837 4337);
PAINT MONO (837 4337);
DISPLAY INVISIBLE (837 4337);
FORCEPROP 1 LASTPIN (1025 4325) $PN 2
J 0
(987 4337);
DISPLAY 0.787234 (987 4337);
PAINT MONO (987 4337);
DISPLAY INVISIBLE (987 4337);
FORCEPROP 1 LAST PACK_TYPE 0402LF
J 0
(1025 4275);
DISPLAY 0.489362 (1025 4275);
PAINT SKYBLUE (1025 4275);
FORCEPROP 1 LAST TOLERANCE 5%
J 0
(950 4275);
DISPLAY 0.489362 (950 4275);
PAINT SKYBLUE (950 4275);
FORCEPROP 1 LAST MATERIAL CHIP
J 0
(600 4275);
DISPLAY 0.489362 (600 4275);
PAINT SKYBLUE (600 4275);
FORCEPROP 1 LAST VALUE 0
J 2
(925 4275);
DISPLAY 0.489362 (925 4275);
PAINT SKYBLUE (925 4275);
FORCEPROP 1 LAST WATTAGE 1/16W
J 2
(850 4275);
DISPLAY 0.489362 (850 4275);
PAINT SKYBLUE (850 4275);
FORCEPROP 2 LAST CDS_LIB pure_quanta
J 0
(925 4325);
DISPLAY INVISIBLE (925 4325);
FORCEPROP 1 LAST PATH I76
J 0
(875 4475);
DISPLAY 0.978723 (875 4475);
PAINT WHITE (875 4475);
DISPLAY INVISIBLE (875 4475);
FORCEPROP 1 LAST PART_NUMBER CS00002JB13
J 0
(250 4275);
DISPLAY 0.489362 (250 4275);
PAINT SKYBLUE (250 4275);
DISPLAY INVISIBLE (250 4275);
FORCEADD Q_RES..1
(-2525 5225);
FORCEPROP 1 LAST LOCATION PR245
J 0
(-2550 5275);
DISPLAY 0.489362 (-2550 5275);
PAINT SKYBLUE (-2550 5275);
FORCEPROP 0 LAST $SEC 1
J 0
(-2575 5325);
DISPLAY 0.680851 (-2575 5325);
PAINT MONO (-2575 5325);
DISPLAY INVISIBLE (-2575 5325);
FORCEPROP 0 LAST CDS_SEC 1
J 0
(-2575 5325);
DISPLAY 1.021277 (-2575 5325);
DISPLAY INVISIBLE (-2575 5325);
FORCEPROP 1 LASTPIN (-2625 5225) $PN 1
J 0
(-2613 5237);
DISPLAY 0.489362 (-2613 5237);
PAINT MONO (-2613 5237);
FORCEPROP 1 LASTPIN (-2425 5225) $PN 2
J 0
(-2463 5237);
DISPLAY 0.489362 (-2463 5237);
PAINT MONO (-2463 5237);
FORCEPROP 1 LAST PACK_TYPE 0402LF
J 0
(-2375 5150);
DISPLAY 0.489362 (-2375 5150);
PAINT SKYBLUE (-2375 5150);
FORCEPROP 1 LAST MATERIAL CHIP
J 0
(-2375 5200);
DISPLAY 0.489362 (-2375 5200);
PAINT SKYBLUE (-2375 5200);
FORCEPROP 1 LAST TOLERANCE 5%
J 0
(-2675 5250);
DISPLAY 0.489362 (-2675 5250);
PAINT SKYBLUE (-2675 5250);
FORCEPROP 1 LAST VALUE 0
J 2
(-2725 5250);
DISPLAY 0.489362 (-2725 5250);
PAINT SKYBLUE (-2725 5250);
FORCEPROP 1 LAST WATTAGE 1/16W
J 2
(-2275 5275);
DISPLAY 0.489362 (-2275 5275);
PAINT SKYBLUE (-2275 5275);
FORCEPROP 2 LAST CDS_LIB pure_quanta
J 0
(-2525 5225);
DISPLAY INVISIBLE (-2525 5225);
FORCEPROP 1 LAST PATH I77
J 0
(-2575 5375);
DISPLAY 0.978723 (-2575 5375);
PAINT WHITE (-2575 5375);
DISPLAY INVISIBLE (-2575 5375);
FORCEPROP 1 LAST PART_NUMBER CS00002JB13
J 0
(-2900 5150);
DISPLAY 0.489362 (-2900 5150);
PAINT SKYBLUE (-2900 5150);
DISPLAY INVISIBLE (-2900 5150);
FORCEADD VCC_CORE..1
(-2675 5525);
FORCEPROP 3 LASTPIN (-2675 5475) SIG_NAME PVDDCR_CPU1_P1\g
J 0
(-2665 5485);
DISPLAY 0.659574 (-2665 5485);
PAINT MONO (-2665 5485);
DISPLAY INVISIBLE (-2665 5485);
FORCEPROP 1 LAST HDL_POWER PVDDCR_CPU1_P1
J 1
(-2675 5575);
DISPLAY 0.489362 (-2675 5575);
PAINT GREEN (-2675 5575);
FORCEPROP 2 LAST CDS_LIB pure_quanta_power
J 0
(-2675 5525);
DISPLAY INVISIBLE (-2675 5525);
FORCEPROP 1 LAST PATH I78
J 0
(-2625 5550);
DISPLAY 0.872340 (-2625 5550);
PAINT AQUA (-2625 5550);
DISPLAY INVISIBLE (-2625 5550);
FORCEADD Q_CAP..1
(-2075 5050);
FORCEPROP 1 LAST LOCATION PC358
J 0
(-2025 5175);
DISPLAY 0.489362 (-2025 5175);
PAINT SKYBLUE (-2025 5175);
FORCEPROP 0 LAST $SEC 1
J 0
(-2025 5175);
DISPLAY 0.680851 (-2025 5175);
PAINT MONO (-2025 5175);
DISPLAY INVISIBLE (-2025 5175);
FORCEPROP 0 LAST CDS_SEC 1
J 0
(-2025 5175);
DISPLAY 1.021277 (-2025 5175);
DISPLAY INVISIBLE (-2025 5175);
FORCEPROP 1 LASTPIN (-2075 5150) $PN 1
J 0
(-2065 5130);
DISPLAY 0.489362 (-2065 5130);
PAINT MONO (-2065 5130);
FORCEPROP 1 LASTPIN (-2075 4950) $PN 2
J 0
(-2065 4930);
DISPLAY 0.489362 (-2065 4930);
PAINT MONO (-2065 4930);
FORCEPROP 1 LAST PACK_TYPE 0402
J 0
(-2025 4925);
DISPLAY 0.489362 (-2025 4925);
PAINT SKYBLUE (-2025 4925);
FORCEPROP 1 LAST TOLERANCE 10%
J 0
(-2025 5025);
DISPLAY 0.489362 (-2025 5025);
PAINT SKYBLUE (-2025 5025);
FORCEPROP 1 LAST VOLTAGE 50V
J 0
(-2025 5075);
DISPLAY 0.489362 (-2025 5075);
PAINT SKYBLUE (-2025 5075);
FORCEPROP 1 LAST MATERIAL X7R
J 0
(-2025 4975);
DISPLAY 0.489362 (-2025 4975);
PAINT SKYBLUE (-2025 4975);
FORCEPROP 1 LAST VALUE 3300PF
J 0
(-2025 5125);
DISPLAY 0.489362 (-2025 5125);
PAINT SKYBLUE (-2025 5125);
FORCEPROP 2 LAST CDS_LIB pure_quanta
J 0
(-2075 5050);
DISPLAY INVISIBLE (-2075 5050);
FORCEPROP 1 LAST PATH I79
J 0
(-2025 5200);
DISPLAY 0.978723 (-2025 5200);
PAINT WHITE (-2025 5200);
DISPLAY INVISIBLE (-2025 5200);
FORCEPROP 1 LAST PART_NUMBER TMP_QCH2336K1B12
J 0
(-2025 4875);
DISPLAY 0.489362 (-2025 4875);
PAINT SKYBLUE (-2025 4875);
DISPLAY INVISIBLE (-2025 4875);
FORCEADD Q_RES..2
(-3050 1700);
FORCEPROP 1 LAST LOCATION PR231
J 0
(-3005 1825);
DISPLAY 0.489362 (-3005 1825);
PAINT SKYBLUE (-3005 1825);
FORCEPROP 0 LAST $SEC 1
J 0
(-3000 1875);
DISPLAY 0.680851 (-3000 1875);
PAINT MONO (-3000 1875);
DISPLAY INVISIBLE (-3000 1875);
FORCEPROP 0 LAST CDS_SEC 1
J 0
(-3000 1875);
DISPLAY 1.021277 (-3000 1875);
DISPLAY INVISIBLE (-3000 1875);
FORCEPROP 1 LASTPIN (-3050 1800) $PN 1
J 0
(-3045 1762);
DISPLAY 0.489362 (-3045 1762);
PAINT MONO (-3045 1762);
FORCEPROP 1 LASTPIN (-3050 1600) $PN 2
J 0
(-3045 1610);
DISPLAY 0.489362 (-3045 1610);
PAINT MONO (-3045 1610);
FORCEPROP 1 LAST VALUE 10K
J 0
(-3005 1775);
DISPLAY 0.489362 (-3005 1775);
PAINT SKYBLUE (-3005 1775);
FORCEPROP 1 LAST PACK_TYPE 0402LF
J 0
(-3010 1525);
DISPLAY 0.489362 (-3010 1525);
PAINT SKYBLUE (-3010 1525);
FORCEPROP 1 LAST TOLERANCE 1%
J 0
(-3005 1725);
DISPLAY 0.489362 (-3005 1725);
PAINT SKYBLUE (-3005 1725);
FORCEPROP 1 LAST WATTAGE 1/16W
J 0
(-3010 1675);
DISPLAY 0.489362 (-3010 1675);
PAINT SKYBLUE (-3010 1675);
FORCEPROP 1 LAST MATERIAL CHIP
J 0
(-3010 1625);
DISPLAY 0.489362 (-3010 1625);
PAINT SKYBLUE (-3010 1625);
FORCEPROP 2 LAST CDS_LIB pure_quanta
J 0
(-3050 1700);
DISPLAY INVISIBLE (-3050 1700);
FORCEPROP 1 LAST PATH I8
J 0
(-3000 1875);
DISPLAY 0.978723 (-3000 1875);
PAINT WHITE (-3000 1875);
DISPLAY INVISIBLE (-3000 1875);
FORCEPROP 1 LAST PART_NUMBER CS31002FB08
J 0
(-3010 1575);
DISPLAY 0.489362 (-3010 1575);
PAINT SKYBLUE (-3010 1575);
DISPLAY INVISIBLE (-3010 1575);
FORCEADD Q_RES..1
(-2175 5775);
FORCEPROP 1 LAST LOCATION R8250
J 0
(-2375 5775);
DISPLAY 0.489362 (-2375 5775);
PAINT SKYBLUE (-2375 5775);
FORCEPROP 0 LAST $SEC 1
J 0
(-2375 5800);
DISPLAY 0.680851 (-2375 5800);
PAINT MONO (-2375 5800);
DISPLAY INVISIBLE (-2375 5800);
FORCEPROP 0 LAST CDS_SEC 1
J 0
(-2375 5800);
DISPLAY 1.021277 (-2375 5800);
DISPLAY INVISIBLE (-2375 5800);
FORCEPROP 1 LASTPIN (-2275 5775) $PN 1
J 0
(-2263 5787);
DISPLAY 0.489362 (-2263 5787);
PAINT MONO (-2263 5787);
FORCEPROP 1 LASTPIN (-2075 5775) $PN 2
J 0
(-2113 5787);
DISPLAY 0.489362 (-2113 5787);
PAINT MONO (-2113 5787);
FORCEPROP 1 LAST MATERIAL CHIP
J 0
(-2500 5725);
DISPLAY 0.489362 (-2500 5725);
PAINT SKYBLUE (-2500 5725);
FORCEPROP 1 LAST PACK_TYPE 0402LF
J 0
(-2075 5725);
DISPLAY 0.489362 (-2075 5725);
PAINT SKYBLUE (-2075 5725);
FORCEPROP 1 LAST TOLERANCE 5%
J 0
(-2150 5725);
DISPLAY 0.489362 (-2150 5725);
PAINT SKYBLUE (-2150 5725);
FORCEPROP 1 LAST WATTAGE 1/16W
J 2
(-2250 5725);
DISPLAY 0.489362 (-2250 5725);
PAINT SKYBLUE (-2250 5725);
FORCEPROP 1 LAST VALUE 33
J 2
(-2175 5725);
DISPLAY 0.489362 (-2175 5725);
PAINT SKYBLUE (-2175 5725);
FORCEPROP 2 LAST CDS_LIB pure_quanta
J 0
(-2175 5775);
DISPLAY INVISIBLE (-2175 5775);
FORCEPROP 1 LAST PATH I80
J 0
(-2225 5925);
DISPLAY 0.978723 (-2225 5925);
PAINT WHITE (-2225 5925);
DISPLAY INVISIBLE (-2225 5925);
FORCEPROP 1 LAST PART_NUMBER CS03302JB10
J 0
(-2850 5725);
DISPLAY 0.489362 (-2850 5725);
PAINT SKYBLUE (-2850 5725);
DISPLAY INVISIBLE (-2850 5725);
FORCEADD Q_RES..1
(-2175 5925);
FORCEPROP 1 LAST LOCATION R8249
J 0
(-2375 5925);
DISPLAY 0.489362 (-2375 5925);
PAINT SKYBLUE (-2375 5925);
FORCEPROP 0 LAST $SEC 1
J 0
(-2375 5950);
DISPLAY 0.680851 (-2375 5950);
PAINT MONO (-2375 5950);
DISPLAY INVISIBLE (-2375 5950);
FORCEPROP 0 LAST CDS_SEC 1
J 0
(-2375 5950);
DISPLAY 1.021277 (-2375 5950);
DISPLAY INVISIBLE (-2375 5950);
FORCEPROP 1 LASTPIN (-2275 5925) $PN 1
J 0
(-2263 5937);
DISPLAY 0.489362 (-2263 5937);
PAINT MONO (-2263 5937);
FORCEPROP 1 LASTPIN (-2075 5925) $PN 2
J 0
(-2113 5937);
DISPLAY 0.489362 (-2113 5937);
PAINT MONO (-2113 5937);
FORCEPROP 1 LAST MATERIAL CHIP
J 0
(-2500 5875);
DISPLAY 0.489362 (-2500 5875);
PAINT SKYBLUE (-2500 5875);
FORCEPROP 1 LAST PACK_TYPE 0402LF
J 0
(-2075 5875);
DISPLAY 0.489362 (-2075 5875);
PAINT SKYBLUE (-2075 5875);
FORCEPROP 1 LAST TOLERANCE 5%
J 0
(-2150 5875);
DISPLAY 0.489362 (-2150 5875);
PAINT SKYBLUE (-2150 5875);
FORCEPROP 1 LAST VALUE 0
J 2
(-2175 5875);
DISPLAY 0.489362 (-2175 5875);
PAINT SKYBLUE (-2175 5875);
FORCEPROP 1 LAST WATTAGE 1/16W
J 2
(-2250 5875);
DISPLAY 0.489362 (-2250 5875);
PAINT SKYBLUE (-2250 5875);
FORCEPROP 2 LAST CDS_LIB pure_quanta
J 0
(-2175 5925);
DISPLAY INVISIBLE (-2175 5925);
FORCEPROP 1 LAST PATH I81
J 0
(-2225 6075);
DISPLAY 0.978723 (-2225 6075);
PAINT WHITE (-2225 6075);
DISPLAY INVISIBLE (-2225 6075);
FORCEPROP 1 LAST PART_NUMBER CS00002JB13
J 0
(-2850 5875);
DISPLAY 0.489362 (-2850 5875);
PAINT SKYBLUE (-2850 5875);
DISPLAY INVISIBLE (-2850 5875);
FORCEADD Q_RES..1
(-2875 6475);
FORCEPROP 1 LAST LOCATION R8238
J 0
(-2925 6525);
DISPLAY 0.489362 (-2925 6525);
PAINT SKYBLUE (-2925 6525);
FORCEPROP 0 LAST $SEC 1
J 0
(-2475 6600);
DISPLAY 0.680851 (-2475 6600);
PAINT MONO (-2475 6600);
DISPLAY INVISIBLE (-2475 6600);
FORCEPROP 0 LAST CDS_SEC 1
J 0
(-2475 6600);
DISPLAY 1.021277 (-2475 6600);
DISPLAY INVISIBLE (-2475 6600);
FORCEPROP 1 LASTPIN (-2975 6475) $PN 1
J 0
(-2963 6487);
DISPLAY 0.489362 (-2963 6487);
PAINT MONO (-2963 6487);
FORCEPROP 1 LASTPIN (-2775 6475) $PN 2
J 0
(-2813 6487);
DISPLAY 0.489362 (-2813 6487);
PAINT MONO (-2813 6487);
FORCEPROP 1 LAST PACK_TYPE 0402LF
J 0
(-2250 6525);
DISPLAY 0.489362 (-2250 6525);
PAINT SKYBLUE (-2250 6525);
FORCEPROP 1 LAST MATERIAL CHIP
J 0
(-2750 6575);
DISPLAY 0.489362 (-2750 6575);
PAINT SKYBLUE (-2750 6575);
FORCEPROP 1 LAST WATTAGE 1/16W
J 2
(-2475 6575);
DISPLAY 0.489362 (-2475 6575);
PAINT SKYBLUE (-2475 6575);
FORCEPROP 1 LAST VALUE 49.9
J 2
(-2350 6525);
DISPLAY 0.489362 (-2350 6525);
PAINT SKYBLUE (-2350 6525);
FORCEPROP 1 LAST TOLERANCE 1%
J 0
(-2325 6525);
DISPLAY 0.489362 (-2325 6525);
PAINT SKYBLUE (-2325 6525);
FORCEPROP 2 LAST CDS_LIB pure_quanta
J 0
(-2875 6475);
DISPLAY INVISIBLE (-2875 6475);
FORCEPROP 1 LAST PATH I82
J 0
(-2925 6625);
DISPLAY 0.978723 (-2925 6625);
PAINT WHITE (-2925 6625);
DISPLAY INVISIBLE (-2925 6625);
FORCEPROP 1 LAST PART_NUMBER CS04992FB07
J 0
(-2750 6525);
DISPLAY 0.489362 (-2750 6525);
PAINT SKYBLUE (-2750 6525);
DISPLAY INVISIBLE (-2750 6525);
FORCEADD Q_RES..1
(-2875 6325);
FORCEPROP 1 LAST LOCATION PR239
J 0
(-2925 6375);
DISPLAY 0.489362 (-2925 6375);
PAINT SKYBLUE (-2925 6375);
FORCEPROP 0 LAST $SEC 1
J 0
(-2475 6450);
DISPLAY 0.680851 (-2475 6450);
PAINT MONO (-2475 6450);
DISPLAY INVISIBLE (-2475 6450);
FORCEPROP 0 LAST CDS_SEC 1
J 0
(-2475 6450);
DISPLAY 1.021277 (-2475 6450);
DISPLAY INVISIBLE (-2475 6450);
FORCEPROP 1 LASTPIN (-2975 6325) $PN 1
J 0
(-2963 6337);
DISPLAY 0.489362 (-2963 6337);
PAINT MONO (-2963 6337);
FORCEPROP 1 LASTPIN (-2775 6325) $PN 2
J 0
(-2813 6337);
DISPLAY 0.489362 (-2813 6337);
PAINT MONO (-2813 6337);
FORCEPROP 1 LAST MATERIAL CHIP
J 0
(-2750 6425);
DISPLAY 0.489362 (-2750 6425);
PAINT SKYBLUE (-2750 6425);
FORCEPROP 1 LAST VALUE 0
J 2
(-2375 6375);
DISPLAY 0.489362 (-2375 6375);
PAINT SKYBLUE (-2375 6375);
FORCEPROP 1 LAST WATTAGE 1/16W
J 2
(-2475 6425);
DISPLAY 0.489362 (-2475 6425);
PAINT SKYBLUE (-2475 6425);
FORCEPROP 1 LAST TOLERANCE 5%
J 0
(-2350 6375);
DISPLAY 0.489362 (-2350 6375);
PAINT SKYBLUE (-2350 6375);
FORCEPROP 1 LAST PACK_TYPE 0402LF
J 0
(-2275 6375);
DISPLAY 0.489362 (-2275 6375);
PAINT SKYBLUE (-2275 6375);
FORCEPROP 2 LAST CDS_LIB pure_quanta
J 0
(-2875 6325);
DISPLAY INVISIBLE (-2875 6325);
FORCEPROP 1 LAST PATH I83
J 0
(-2925 6475);
DISPLAY 0.978723 (-2925 6475);
PAINT WHITE (-2925 6475);
DISPLAY INVISIBLE (-2925 6475);
FORCEPROP 1 LAST PART_NUMBER CS00002JB13
J 0
(-2750 6375);
DISPLAY 0.489362 (-2750 6375);
PAINT SKYBLUE (-2750 6375);
DISPLAY INVISIBLE (-2750 6375);
FORCEADD Q_RES..1
(-2175 6075);
FORCEPROP 1 LAST LOCATION R8248
J 0
(-2375 6075);
DISPLAY 0.489362 (-2375 6075);
PAINT SKYBLUE (-2375 6075);
FORCEPROP 0 LAST $SEC 1
J 0
(-2225 6175);
DISPLAY 0.680851 (-2225 6175);
PAINT MONO (-2225 6175);
DISPLAY INVISIBLE (-2225 6175);
FORCEPROP 0 LAST CDS_SEC 1
J 0
(-2225 6175);
DISPLAY 1.021277 (-2225 6175);
DISPLAY INVISIBLE (-2225 6175);
FORCEPROP 1 LASTPIN (-2275 6075) $PN 1
J 0
(-2263 6087);
DISPLAY 0.489362 (-2263 6087);
PAINT MONO (-2263 6087);
FORCEPROP 1 LASTPIN (-2075 6075) $PN 2
J 0
(-2113 6087);
DISPLAY 0.489362 (-2113 6087);
PAINT MONO (-2113 6087);
FORCEPROP 1 LAST MATERIAL CHIP
J 0
(-2500 6025);
DISPLAY 0.489362 (-2500 6025);
PAINT SKYBLUE (-2500 6025);
FORCEPROP 1 LAST TOLERANCE 5%
J 0
(-2150 6025);
DISPLAY 0.489362 (-2150 6025);
PAINT SKYBLUE (-2150 6025);
FORCEPROP 1 LAST VALUE 0
J 2
(-2175 6025);
DISPLAY 0.489362 (-2175 6025);
PAINT SKYBLUE (-2175 6025);
FORCEPROP 1 LAST PACK_TYPE 0402LF
J 0
(-2075 6025);
DISPLAY 0.489362 (-2075 6025);
PAINT SKYBLUE (-2075 6025);
FORCEPROP 1 LAST WATTAGE 1/16W
J 2
(-2250 6025);
DISPLAY 0.489362 (-2250 6025);
PAINT SKYBLUE (-2250 6025);
FORCEPROP 2 LAST CDS_LIB pure_quanta
J 0
(-2175 6075);
DISPLAY INVISIBLE (-2175 6075);
FORCEPROP 1 LAST PATH I84
J 0
(-2225 6225);
DISPLAY 0.978723 (-2225 6225);
PAINT WHITE (-2225 6225);
DISPLAY INVISIBLE (-2225 6225);
FORCEPROP 1 LAST PART_NUMBER CS00002JB13
J 0
(-2850 6025);
DISPLAY 0.489362 (-2850 6025);
PAINT SKYBLUE (-2850 6025);
DISPLAY INVISIBLE (-2850 6025);
FORCEADD Q_CAP..2
(-2050 6950);
FORCEPROP 1 LAST LOCATION C8359
J 1
(-2225 6950);
DISPLAY 0.489362 (-2225 6950);
PAINT SKYBLUE (-2225 6950);
FORCEPROP 0 LAST $SEC 1
J 0
(-2100 7050);
DISPLAY 0.680851 (-2100 7050);
PAINT MONO (-2100 7050);
DISPLAY INVISIBLE (-2100 7050);
FORCEPROP 0 LAST CDS_SEC 1
J 0
(-2100 7050);
DISPLAY 1.021277 (-2100 7050);
DISPLAY INVISIBLE (-2100 7050);
FORCEPROP 1 LASTPIN (-2150 6950) $PN 1
J 0
(-2160 6965);
DISPLAY 0.489362 (-2160 6965);
PAINT MONO (-2160 6965);
FORCEPROP 1 LASTPIN (-1950 6950) $PN 2
J 0
(-1965 6965);
DISPLAY 0.489362 (-1965 6965);
PAINT MONO (-1965 6965);
FORCEPROP 1 LAST TOLERANCE 5%
J 2
(-1400 6900);
DISPLAY 0.489362 (-1400 6900);
PAINT SKYBLUE (-1400 6900);
FORCEPROP 1 LAST VOLTAGE 50V
J 0
(-1700 6950);
DISPLAY 0.489362 (-1700 6950);
PAINT SKYBLUE (-1700 6950);
FORCEPROP 1 LAST PACK_TYPE 0402
J 1
(-1550 6900);
DISPLAY 0.489362 (-1550 6900);
PAINT SKYBLUE (-1550 6900);
FORCEPROP 1 LAST MATERIAL X7R
J 0
(-1575 6950);
DISPLAY 0.489362 (-1575 6950);
PAINT SKYBLUE (-1575 6950);
FORCEPROP 1 LAST VALUE 1000PF
J 2
(-1725 6950);
DISPLAY 0.489362 (-1725 6950);
PAINT SKYBLUE (-1725 6950);
FORCEPROP 2 LAST CDS_LIB pure_quanta
J 0
(-2050 6950);
DISPLAY INVISIBLE (-2050 6950);
FORCEPROP 1 LAST PATH I85
J 0
(-2050 7150);
DISPLAY 0.978723 (-2050 7150);
PAINT WHITE (-2050 7150);
DISPLAY INVISIBLE (-2050 7150);
FORCEPROP 1 LAST PART_NUMBER TMP_QCH21006JB10
J 1
(-1775 6900);
DISPLAY 0.489362 (-1775 6900);
PAINT SKYBLUE (-1775 6900);
DISPLAY INVISIBLE (-1775 6900);
FORCEADD UNIVERSAL_GND..1
R 1
(-1325 6950);
FORCEPROP 3 LASTPIN (-1375 6950) SIG_NAME GND\g
J 0
(-1365 6960);
DISPLAY 0.659574 (-1365 6960);
PAINT MONO (-1365 6960);
DISPLAY INVISIBLE (-1365 6960);
FORCEPROP 2 LAST CDS_LIB pure_quanta_power
J 0
(-1325 6950);
PAINT MONO (-1325 6950);
DISPLAY INVISIBLE (-1325 6950);
FORCEPROP 1 LAST HDL_POWER GND
R 1
J 1
(-1250 6975);
DISPLAY 0.872340 (-1250 6975);
PAINT GREEN (-1250 6975);
DISPLAY INVISIBLE (-1250 6975);
FORCEPROP 1 LAST PATH I86
R 1
J 0
(-1325 7025);
DISPLAY 0.872340 (-1325 7025);
PAINT AQUA (-1325 7025);
DISPLAY INVISIBLE (-1325 7025);
FORCEADD Q_RES..1
(-2875 7075);
FORCEPROP 1 LAST LOCATION R8235
J 0
(-3075 7075);
DISPLAY 0.489362 (-3075 7075);
PAINT SKYBLUE (-3075 7075);
FORCEPROP 0 LAST $SEC 1
J 0
(-2925 7175);
DISPLAY 0.680851 (-2925 7175);
PAINT MONO (-2925 7175);
DISPLAY INVISIBLE (-2925 7175);
FORCEPROP 0 LAST CDS_SEC 1
J 0
(-2925 7175);
DISPLAY 1.021277 (-2925 7175);
DISPLAY INVISIBLE (-2925 7175);
FORCEPROP 1 LASTPIN (-2975 7075) $PN 1
J 0
(-2963 7087);
DISPLAY 0.489362 (-2963 7087);
PAINT MONO (-2963 7087);
FORCEPROP 1 LASTPIN (-2775 7075) $PN 2
J 0
(-2813 7087);
DISPLAY 0.489362 (-2813 7087);
PAINT MONO (-2813 7087);
FORCEPROP 1 LAST WATTAGE 1/16W
J 2
(-2500 7175);
DISPLAY 0.489362 (-2500 7175);
PAINT SKYBLUE (-2500 7175);
FORCEPROP 1 LAST TOLERANCE 5%
J 0
(-2700 7075);
DISPLAY 0.489362 (-2700 7075);
PAINT SKYBLUE (-2700 7075);
FORCEPROP 1 LAST VALUE 0
J 2
(-2725 7075);
DISPLAY 0.489362 (-2725 7075);
PAINT SKYBLUE (-2725 7075);
FORCEPROP 1 LAST PACK_TYPE 0402LF
J 0
(-2625 7075);
DISPLAY 0.489362 (-2625 7075);
PAINT SKYBLUE (-2625 7075);
FORCEPROP 1 LAST MATERIAL CHIP
J 0
(-2750 7175);
DISPLAY 0.489362 (-2750 7175);
PAINT SKYBLUE (-2750 7175);
FORCEPROP 2 LAST CDS_LIB pure_quanta
J 0
(-2875 7075);
DISPLAY INVISIBLE (-2875 7075);
FORCEPROP 1 LAST PATH I87
J 0
(-2925 7225);
DISPLAY 0.978723 (-2925 7225);
PAINT WHITE (-2925 7225);
DISPLAY INVISIBLE (-2925 7225);
FORCEPROP 1 LAST PART_NUMBER CS00002JB13
J 0
(-2750 7125);
DISPLAY 0.489362 (-2750 7125);
PAINT SKYBLUE (-2750 7125);
DISPLAY INVISIBLE (-2750 7125);
FORCEADD Q_RES..1
(-2875 7225);
FORCEPROP 1 LAST LOCATION R8234
J 0
(-3075 7225);
DISPLAY 0.489362 (-3075 7225);
PAINT SKYBLUE (-3075 7225);
FORCEPROP 0 LAST $SEC 1
J 0
(-2925 7325);
DISPLAY 0.680851 (-2925 7325);
PAINT MONO (-2925 7325);
DISPLAY INVISIBLE (-2925 7325);
FORCEPROP 0 LAST CDS_SEC 1
J 0
(-2925 7325);
DISPLAY 1.021277 (-2925 7325);
DISPLAY INVISIBLE (-2925 7325);
FORCEPROP 1 LASTPIN (-2975 7225) $PN 1
J 0
(-2963 7237);
DISPLAY 0.489362 (-2963 7237);
PAINT MONO (-2963 7237);
FORCEPROP 1 LASTPIN (-2775 7225) $PN 2
J 0
(-2813 7237);
DISPLAY 0.489362 (-2813 7237);
PAINT MONO (-2813 7237);
FORCEPROP 1 LAST MATERIAL CHIP
J 0
(-2750 7325);
DISPLAY 0.489362 (-2750 7325);
PAINT SKYBLUE (-2750 7325);
FORCEPROP 1 LAST PACK_TYPE 0402LF
J 0
(-2625 7225);
DISPLAY 0.489362 (-2625 7225);
PAINT SKYBLUE (-2625 7225);
FORCEPROP 1 LAST VALUE 33
J 2
(-2725 7225);
DISPLAY 0.489362 (-2725 7225);
PAINT SKYBLUE (-2725 7225);
FORCEPROP 1 LAST WATTAGE 1/16W
J 2
(-2500 7325);
DISPLAY 0.489362 (-2500 7325);
PAINT SKYBLUE (-2500 7325);
FORCEPROP 1 LAST TOLERANCE 5%
J 0
(-2700 7225);
DISPLAY 0.489362 (-2700 7225);
PAINT SKYBLUE (-2700 7225);
FORCEPROP 2 LAST CDS_LIB pure_quanta
J 0
(-2875 7225);
DISPLAY INVISIBLE (-2875 7225);
FORCEPROP 1 LAST PATH I88
J 0
(-2925 7375);
DISPLAY 0.978723 (-2925 7375);
PAINT WHITE (-2925 7375);
DISPLAY INVISIBLE (-2925 7375);
FORCEPROP 1 LAST PART_NUMBER CS03302JB10
J 0
(-2750 7275);
DISPLAY 0.489362 (-2750 7275);
PAINT SKYBLUE (-2750 7275);
DISPLAY INVISIBLE (-2750 7275);
FORCEADD Q_RES..1
(-2875 7375);
FORCEPROP 1 LAST LOCATION R8233
J 0
(-3075 7375);
DISPLAY 0.489362 (-3075 7375);
PAINT SKYBLUE (-3075 7375);
FORCEPROP 0 LAST $SEC 1
J 0
(-2925 7475);
DISPLAY 0.680851 (-2925 7475);
PAINT MONO (-2925 7475);
DISPLAY INVISIBLE (-2925 7475);
FORCEPROP 0 LAST CDS_SEC 1
J 0
(-2925 7475);
DISPLAY 1.021277 (-2925 7475);
DISPLAY INVISIBLE (-2925 7475);
FORCEPROP 1 LASTPIN (-2975 7375) $PN 1
J 0
(-2963 7387);
DISPLAY 0.489362 (-2963 7387);
PAINT MONO (-2963 7387);
FORCEPROP 1 LASTPIN (-2775 7375) $PN 2
J 0
(-2813 7387);
DISPLAY 0.489362 (-2813 7387);
PAINT MONO (-2813 7387);
FORCEPROP 1 LAST TOLERANCE 1%
J 0
(-2675 7375);
DISPLAY 0.489362 (-2675 7375);
PAINT SKYBLUE (-2675 7375);
FORCEPROP 1 LAST MATERIAL CHIP
J 0
(-2750 7475);
DISPLAY 0.489362 (-2750 7475);
PAINT SKYBLUE (-2750 7475);
FORCEPROP 1 LAST VALUE 1K
J 2
(-2700 7375);
DISPLAY 0.489362 (-2700 7375);
PAINT SKYBLUE (-2700 7375);
FORCEPROP 1 LAST WATTAGE 1/16W
J 2
(-2500 7475);
DISPLAY 0.489362 (-2500 7475);
PAINT SKYBLUE (-2500 7475);
FORCEPROP 1 LAST PACK_TYPE 0402LF
J 0
(-2575 7375);
DISPLAY 0.489362 (-2575 7375);
PAINT SKYBLUE (-2575 7375);
FORCEPROP 2 LAST CDS_LIB pure_quanta
J 0
(-2875 7375);
DISPLAY INVISIBLE (-2875 7375);
FORCEPROP 1 LAST PATH I89
J 0
(-2925 7525);
DISPLAY 0.978723 (-2925 7525);
PAINT WHITE (-2925 7525);
DISPLAY INVISIBLE (-2925 7525);
FORCEPROP 1 LAST PART_NUMBER CS21002FB06
J 0
(-2750 7425);
DISPLAY 0.489362 (-2750 7425);
PAINT SKYBLUE (-2750 7425);
DISPLAY INVISIBLE (-2750 7425);
FORCEADD Q_RES..1
(-3400 1875);
FORCEPROP 1 LAST LOCATION PR230
J 0
(-3625 1875);
DISPLAY 0.489362 (-3625 1875);
PAINT SKYBLUE (-3625 1875);
FORCEPROP 0 LAST $SEC 1
J 0
(-3450 1975);
DISPLAY 0.680851 (-3450 1975);
PAINT MONO (-3450 1975);
DISPLAY INVISIBLE (-3450 1975);
FORCEPROP 0 LAST CDS_SEC 1
J 0
(-3450 1975);
DISPLAY 1.021277 (-3450 1975);
DISPLAY INVISIBLE (-3450 1975);
FORCEPROP 1 LASTPIN (-3500 1875) $PN 1
J 0
(-3488 1887);
DISPLAY 0.489362 (-3488 1887);
PAINT MONO (-3488 1887);
FORCEPROP 1 LASTPIN (-3300 1875) $PN 2
J 0
(-3338 1887);
DISPLAY 0.489362 (-3338 1887);
PAINT MONO (-3338 1887);
FORCEPROP 1 LAST VALUE 40.2K
J 2
(-3175 1900);
DISPLAY 0.489362 (-3175 1900);
PAINT SKYBLUE (-3175 1900);
FORCEPROP 1 LAST TOLERANCE 1%
J 0
(-3150 1900);
DISPLAY 0.489362 (-3150 1900);
PAINT SKYBLUE (-3150 1900);
FORCEPROP 1 LAST MATERIAL CHIP
J 0
(-2925 1900);
DISPLAY 0.489362 (-2925 1900);
PAINT SKYBLUE (-2925 1900);
FORCEPROP 1 LAST PACK_TYPE 0402LF
J 0
(-3075 1900);
DISPLAY 0.489362 (-3075 1900);
PAINT SKYBLUE (-3075 1900);
FORCEPROP 2 LAST CDS_LIB pure_quanta
J 0
(-3400 1875);
DISPLAY INVISIBLE (-3400 1875);
FORCEPROP 1 LAST WATTAGE 1/16W
J 2
(-3025 1775);
DISPLAY 0.510638 (-3025 1775);
PAINT SKYBLUE (-3025 1775);
DISPLAY INVISIBLE (-3025 1775);
FORCEPROP 1 LAST PATH I9
J 0
(-3450 2025);
DISPLAY 0.978723 (-3450 2025);
PAINT WHITE (-3450 2025);
DISPLAY INVISIBLE (-3450 2025);
FORCEPROP 1 LAST PART_NUMBER CS34022FB04
J 0
(-3500 1800);
DISPLAY 0.510638 (-3500 1800);
PAINT SKYBLUE (-3500 1800);
DISPLAY INVISIBLE (-3500 1800);
FORCEADD Q_CAP..2
(-2025 7375);
FORCEPROP 1 LAST LOCATION C8360
J 1
(-2225 7375);
DISPLAY 0.489362 (-2225 7375);
PAINT SKYBLUE (-2225 7375);
FORCEPROP 0 LAST $SEC 1
J 0
(-2075 7475);
DISPLAY 0.680851 (-2075 7475);
PAINT MONO (-2075 7475);
DISPLAY INVISIBLE (-2075 7475);
FORCEPROP 0 LAST CDS_SEC 1
J 0
(-2075 7475);
DISPLAY 1.021277 (-2075 7475);
DISPLAY INVISIBLE (-2075 7475);
FORCEPROP 1 LASTPIN (-2125 7375) $PN 1
J 0
(-2135 7390);
DISPLAY 0.489362 (-2135 7390);
PAINT MONO (-2135 7390);
FORCEPROP 1 LASTPIN (-1925 7375) $PN 2
J 0
(-1940 7390);
DISPLAY 0.489362 (-1940 7390);
PAINT MONO (-1940 7390);
FORCEPROP 1 LAST TOLERANCE 5%
J 2
(-1375 7325);
DISPLAY 0.489362 (-1375 7325);
PAINT SKYBLUE (-1375 7325);
FORCEPROP 1 LAST PACK_TYPE 0402
J 1
(-1525 7325);
DISPLAY 0.489362 (-1525 7325);
PAINT SKYBLUE (-1525 7325);
FORCEPROP 1 LAST VOLTAGE 50V
J 0
(-1675 7375);
DISPLAY 0.489362 (-1675 7375);
PAINT SKYBLUE (-1675 7375);
FORCEPROP 1 LAST VALUE 1000PF
J 2
(-1700 7375);
DISPLAY 0.489362 (-1700 7375);
PAINT SKYBLUE (-1700 7375);
FORCEPROP 1 LAST MATERIAL EMPTY
J 0
(-1550 7375);
DISPLAY 0.489362 (-1550 7375);
PAINT RED (-1550 7375);
FORCEPROP 2 LAST CDS_LIB pure_quanta
J 0
(-2025 7375);
DISPLAY INVISIBLE (-2025 7375);
FORCEPROP 1 LAST PATH I90
J 0
(-2025 7575);
DISPLAY 0.978723 (-2025 7575);
PAINT WHITE (-2025 7575);
DISPLAY INVISIBLE (-2025 7575);
FORCEPROP 1 LAST PART_NUMBER TMP_QCH21006JB10
J 1
(-1750 7325);
DISPLAY 0.489362 (-1750 7325);
PAINT SKYBLUE (-1750 7325);
DISPLAY INVISIBLE (-1750 7325);
FORCEADD UNIVERSAL_GND..1
R 1
(-1325 7375);
FORCEPROP 3 LASTPIN (-1375 7375) SIG_NAME GND\g
J 0
(-1365 7385);
DISPLAY 0.659574 (-1365 7385);
PAINT MONO (-1365 7385);
DISPLAY INVISIBLE (-1365 7385);
FORCEPROP 2 LAST CDS_LIB pure_quanta_power
J 0
(-1325 7375);
PAINT MONO (-1325 7375);
DISPLAY INVISIBLE (-1325 7375);
FORCEPROP 1 LAST HDL_POWER GND
R 1
J 1
(-1250 7400);
DISPLAY 0.872340 (-1250 7400);
PAINT GREEN (-1250 7400);
DISPLAY INVISIBLE (-1250 7400);
FORCEPROP 1 LAST PATH I91
R 1
J 0
(-1325 7450);
DISPLAY 0.872340 (-1325 7450);
PAINT AQUA (-1325 7450);
DISPLAY INVISIBLE (-1325 7450);
FORCEADD UNIVERSAL_GND..1
(475 6375);
FORCEPROP 3 LASTPIN (475 6425) SIG_NAME GND\g
J 0
(485 6435);
DISPLAY 0.659574 (485 6435);
PAINT MONO (485 6435);
DISPLAY INVISIBLE (485 6435);
FORCEPROP 2 LAST CDS_LIB pure_quanta_power
J 0
(475 6375);
DISPLAY INVISIBLE (475 6375);
FORCEPROP 1 LAST HDL_POWER GND
J 1
(500 6300);
DISPLAY 0.872340 (500 6300);
PAINT GREEN (500 6300);
DISPLAY INVISIBLE (500 6300);
FORCEPROP 1 LAST PATH I92
J 0
(550 6375);
DISPLAY 0.872340 (550 6375);
PAINT AQUA (550 6375);
DISPLAY INVISIBLE (550 6375);
FORCEADD Q_CAP..1
(475 6600);
FORCEPROP 1 LAST LOCATION PC93
J 0
(525 6700);
DISPLAY 0.489362 (525 6700);
PAINT SKYBLUE (525 6700);
FORCEPROP 0 LAST $SEC 1
J 0
(525 6725);
DISPLAY 0.680851 (525 6725);
PAINT MONO (525 6725);
DISPLAY INVISIBLE (525 6725);
FORCEPROP 0 LAST CDS_SEC 1
J 0
(525 6725);
DISPLAY 1.021277 (525 6725);
DISPLAY INVISIBLE (525 6725);
FORCEPROP 1 LASTPIN (475 6700) $PN 1
J 0
(485 6680);
DISPLAY 0.489362 (485 6680);
PAINT MONO (485 6680);
FORCEPROP 1 LASTPIN (475 6500) $PN 2
J 0
(485 6480);
DISPLAY 0.489362 (485 6480);
PAINT MONO (485 6480);
FORCEPROP 1 LAST PACK_TYPE 0402
J 0
(525 6400);
DISPLAY 0.489362 (525 6400);
PAINT SKYBLUE (525 6400);
FORCEPROP 1 LAST VOLTAGE 25V
J 0
(525 6600);
DISPLAY 0.489362 (525 6600);
PAINT SKYBLUE (525 6600);
FORCEPROP 1 LAST VALUE 0.1UF
J 0
(525 6650);
DISPLAY 0.489362 (525 6650);
PAINT SKYBLUE (525 6650);
FORCEPROP 1 LAST TOLERANCE 10%
J 0
(525 6550);
DISPLAY 0.489362 (525 6550);
PAINT SKYBLUE (525 6550);
FORCEPROP 1 LAST MATERIAL X7R
J 0
(525 6500);
DISPLAY 0.489362 (525 6500);
PAINT SKYBLUE (525 6500);
FORCEPROP 2 LAST CDS_LIB pure_quanta
J 0
(475 6600);
DISPLAY INVISIBLE (475 6600);
FORCEPROP 1 LAST PATH I93
J 0
(525 6750);
DISPLAY 0.978723 (525 6750);
PAINT WHITE (525 6750);
DISPLAY INVISIBLE (525 6750);
FORCEPROP 1 LAST PART_NUMBER CH4104K1B00
J 0
(525 6450);
DISPLAY 0.489362 (525 6450);
PAINT SKYBLUE (525 6450);
DISPLAY INVISIBLE (525 6450);
FORCEADD UNIVERSAL_GND..1
(475 6850);
FORCEPROP 3 LASTPIN (475 6900) SIG_NAME GND\g
J 0
(485 6910);
DISPLAY 0.659574 (485 6910);
PAINT MONO (485 6910);
DISPLAY INVISIBLE (485 6910);
FORCEPROP 2 LAST CDS_LIB pure_quanta_power
J 0
(475 6850);
DISPLAY INVISIBLE (475 6850);
FORCEPROP 1 LAST HDL_POWER GND
J 1
(500 6775);
DISPLAY 0.872340 (500 6775);
PAINT GREEN (500 6775);
DISPLAY INVISIBLE (500 6775);
FORCEPROP 1 LAST PATH I94
J 0
(550 6850);
DISPLAY 0.872340 (550 6850);
PAINT AQUA (550 6850);
DISPLAY INVISIBLE (550 6850);
FORCEADD Q_CAP..1
(475 7075);
FORCEPROP 1 LAST LOCATION PC29
J 0
(525 7175);
DISPLAY 0.489362 (525 7175);
PAINT SKYBLUE (525 7175);
FORCEPROP 0 LAST $SEC 1
J 0
(525 7200);
DISPLAY 0.680851 (525 7200);
PAINT MONO (525 7200);
DISPLAY INVISIBLE (525 7200);
FORCEPROP 0 LAST CDS_SEC 1
J 0
(525 7200);
DISPLAY 1.021277 (525 7200);
DISPLAY INVISIBLE (525 7200);
FORCEPROP 1 LASTPIN (475 7175) $PN 1
J 0
(485 7155);
DISPLAY 0.489362 (485 7155);
PAINT MONO (485 7155);
FORCEPROP 1 LASTPIN (475 6975) $PN 2
J 0
(485 6955);
DISPLAY 0.489362 (485 6955);
PAINT MONO (485 6955);
FORCEPROP 1 LAST PACK_TYPE 0402
J 0
(525 6875);
DISPLAY 0.489362 (525 6875);
PAINT SKYBLUE (525 6875);
FORCEPROP 1 LAST MATERIAL X7R
J 0
(525 6975);
DISPLAY 0.489362 (525 6975);
PAINT SKYBLUE (525 6975);
FORCEPROP 1 LAST VOLTAGE 25V
J 0
(525 7075);
DISPLAY 0.489362 (525 7075);
PAINT SKYBLUE (525 7075);
FORCEPROP 1 LAST VALUE 0.1UF
J 0
(525 7125);
DISPLAY 0.489362 (525 7125);
PAINT SKYBLUE (525 7125);
FORCEPROP 1 LAST TOLERANCE 10%
J 0
(525 7025);
DISPLAY 0.489362 (525 7025);
PAINT SKYBLUE (525 7025);
FORCEPROP 2 LAST CDS_LIB pure_quanta
J 0
(475 7075);
DISPLAY INVISIBLE (475 7075);
FORCEPROP 1 LAST PATH I95
J 0
(525 7225);
DISPLAY 0.978723 (525 7225);
PAINT WHITE (525 7225);
DISPLAY INVISIBLE (525 7225);
FORCEPROP 1 LAST PART_NUMBER CH4104K1B00
J 0
(525 6925);
DISPLAY 0.489362 (525 6925);
PAINT SKYBLUE (525 6925);
DISPLAY INVISIBLE (525 6925);
FORCEADD UNIVERSAL_GND..1
(850 6375);
FORCEPROP 3 LASTPIN (850 6425) SIG_NAME GND\g
J 0
(860 6435);
DISPLAY 0.659574 (860 6435);
PAINT MONO (860 6435);
DISPLAY INVISIBLE (860 6435);
FORCEPROP 2 LAST CDS_LIB pure_quanta_power
J 0
(850 6375);
DISPLAY INVISIBLE (850 6375);
FORCEPROP 1 LAST HDL_POWER GND
J 1
(875 6300);
DISPLAY 0.872340 (875 6300);
PAINT GREEN (875 6300);
DISPLAY INVISIBLE (875 6300);
FORCEPROP 1 LAST PATH I96
J 0
(925 6375);
DISPLAY 0.872340 (925 6375);
PAINT AQUA (925 6375);
DISPLAY INVISIBLE (925 6375);
FORCEADD Q_CAP..1
(850 6575);
FORCEPROP 1 LAST LOCATION PC366
J 0
(900 6700);
DISPLAY 0.489362 (900 6700);
PAINT SKYBLUE (900 6700);
FORCEPROP 2 LAST $SEC 1
J 0
(900 6775);
DISPLAY 0.680851 (900 6775);
PAINT MONO (900 6775);
DISPLAY INVISIBLE (900 6775);
FORCEPROP 2 LAST CDS_SEC 1
J 0
(900 6775);
DISPLAY 1.021277 (900 6775);
DISPLAY INVISIBLE (900 6775);
FORCEPROP 1 LASTPIN (850 6675) $PN 1
J 0
(860 6655);
DISPLAY 0.489362 (860 6655);
FORCEPROP 1 LASTPIN (850 6475) $PN 2
J 0
(860 6455);
DISPLAY 0.489362 (860 6455);
FORCEPROP 1 LAST VALUE 10UF
J 0
(900 6650);
DISPLAY 0.489362 (900 6650);
PAINT SKYBLUE (900 6650);
FORCEPROP 1 LAST VOLTAGE 6.3V
J 0
(900 6600);
DISPLAY 0.489362 (900 6600);
PAINT SKYBLUE (900 6600);
FORCEPROP 1 LAST TOLERANCE 20%
J 0
(900 6550);
DISPLAY 0.489362 (900 6550);
PAINT SKYBLUE (900 6550);
FORCEPROP 1 LAST MATERIAL X6S
J 0
(900 6500);
DISPLAY 0.489362 (900 6500);
PAINT SKYBLUE (900 6500);
FORCEPROP 1 LAST PACK_TYPE C0402
J 0
(900 6450);
DISPLAY 0.489362 (900 6450);
PAINT SKYBLUE (900 6450);
FORCEPROP 2 LAST CDS_LIB pure_quanta
J 0
(850 6575);
PAINT MONO (850 6575);
DISPLAY INVISIBLE (850 6575);
FORCEPROP 1 LAST PATH I97
J 0
(900 6725);
DISPLAY 0.978723 (900 6725);
PAINT WHITE (900 6725);
DISPLAY INVISIBLE (900 6725);
FORCEPROP 1 LAST PART_NUMBER CH6101MEB03
J 0
(900 6400);
DISPLAY 0.489362 (900 6400);
PAINT SKYBLUE (900 6400);
DISPLAY INVISIBLE (900 6400);
FORCEADD UNIVERSAL_GND..1
(850 6850);
FORCEPROP 3 LASTPIN (850 6900) SIG_NAME GND\g
J 0
(860 6910);
DISPLAY 0.659574 (860 6910);
PAINT MONO (860 6910);
DISPLAY INVISIBLE (860 6910);
FORCEPROP 2 LAST CDS_LIB pure_quanta_power
J 0
(850 6850);
DISPLAY INVISIBLE (850 6850);
FORCEPROP 1 LAST HDL_POWER GND
J 1
(875 6775);
DISPLAY 0.872340 (875 6775);
PAINT GREEN (875 6775);
DISPLAY INVISIBLE (875 6775);
FORCEPROP 1 LAST PATH I98
J 0
(925 6850);
DISPLAY 0.872340 (925 6850);
PAINT AQUA (925 6850);
DISPLAY INVISIBLE (925 6850);
FORCEADD Q_CAP..1
(850 7050);
FORCEPROP 1 LAST LOCATION PC365
J 0
(900 7175);
DISPLAY 0.489362 (900 7175);
PAINT SKYBLUE (900 7175);
FORCEPROP 0 LAST $SEC 1
J 0
(900 7225);
DISPLAY 0.680851 (900 7225);
PAINT MONO (900 7225);
DISPLAY INVISIBLE (900 7225);
FORCEPROP 0 LAST CDS_SEC 1
J 0
(900 7225);
DISPLAY 1.021277 (900 7225);
DISPLAY INVISIBLE (900 7225);
FORCEPROP 1 LASTPIN (850 7150) $PN 1
J 0
(860 7130);
DISPLAY 0.489362 (860 7130);
PAINT MONO (860 7130);
FORCEPROP 1 LASTPIN (850 6950) $PN 2
J 0
(860 6930);
DISPLAY 0.489362 (860 6930);
PAINT MONO (860 6930);
FORCEPROP 1 LAST VALUE 1UF
J 0
(900 7125);
DISPLAY 0.489362 (900 7125);
PAINT SKYBLUE (900 7125);
FORCEPROP 1 LAST PACK_TYPE C0402
J 0
(900 6925);
DISPLAY 0.489362 (900 6925);
PAINT SKYBLUE (900 6925);
FORCEPROP 1 LAST VOLTAGE 16V
J 0
(900 7075);
DISPLAY 0.489362 (900 7075);
PAINT SKYBLUE (900 7075);
FORCEPROP 1 LAST TOLERANCE 10%
J 0
(900 7025);
DISPLAY 0.489362 (900 7025);
PAINT SKYBLUE (900 7025);
FORCEPROP 1 LAST MATERIAL X6S
J 0
(900 6975);
DISPLAY 0.489362 (900 6975);
PAINT SKYBLUE (900 6975);
FORCEPROP 2 LAST CDS_LIB pure_quanta
J 0
(850 7050);
DISPLAY INVISIBLE (850 7050);
FORCEPROP 1 LAST PATH I99
J 0
(900 7200);
DISPLAY 0.978723 (900 7200);
PAINT WHITE (900 7200);
DISPLAY INVISIBLE (900 7200);
FORCEPROP 1 LAST PART_NUMBER CH5103KEB01
J 0
(900 6875);
DISPLAY 0.489362 (900 6875);
PAINT SKYBLUE (900 6875);
DISPLAY INVISIBLE (900 6875);
FORCEADD DNS..1
(-4600 6125);
PAINT RED (-4600 6125);
FORCEPROP 2 LAST CDS_LIB mstr_misc
J 0
(-4600 6125);
DISPLAY INVISIBLE (-4600 6125);
FORCEPROP 1 LAST COMMENT_BODY TRUE
R 1
J 0
(-4525 5900);
DISPLAY 0.872340 (-4525 5900);
PAINT GREEN (-4525 5900);
DISPLAY INVISIBLE (-4525 5900);
FORCEADD DNS..1
(-4425 6100);
PAINT RED (-4425 6100);
FORCEPROP 2 LAST CDS_LIB mstr_misc
J 0
(-4425 6100);
DISPLAY INVISIBLE (-4425 6100);
FORCEPROP 1 LAST COMMENT_BODY TRUE
R 1
J 0
(-4350 5875);
DISPLAY 0.872340 (-4350 5875);
PAINT GREEN (-4350 5875);
DISPLAY INVISIBLE (-4350 5875);
FORCEADD DNS..1
(-4550 2300);
PAINT RED (-4550 2300);
FORCEPROP 2 LAST CDS_LIB mstr_misc
J 0
(-4550 2300);
DISPLAY INVISIBLE (-4550 2300);
FORCEPROP 1 LAST COMMENT_BODY TRUE
R 1
J 0
(-4475 2075);
DISPLAY 0.872340 (-4475 2075);
PAINT GREEN (-4475 2075);
DISPLAY INVISIBLE (-4475 2075);
FORCEADD DNS..1
(-2025 7400);
PAINT RED (-2025 7400);
FORCEPROP 2 LAST CDS_LIB mstr_misc
J 0
(-2025 7400);
DISPLAY INVISIBLE (-2025 7400);
FORCEPROP 1 LAST COMMENT_BODY TRUE
R 1
J 0
(-1950 7175);
DISPLAY 0.872340 (-1950 7175);
PAINT GREEN (-1950 7175);
DISPLAY INVISIBLE (-1950 7175);
FORCEADD DNS..1
(-1775 1500);
PAINT RED (-1775 1500);
FORCEPROP 2 LAST CDS_LIB mstr_misc
J 0
(-1775 1500);
DISPLAY INVISIBLE (-1775 1500);
FORCEPROP 1 LAST COMMENT_BODY TRUE
R 1
J 0
(-1700 1275);
DISPLAY 0.872340 (-1700 1275);
PAINT GREEN (-1700 1275);
DISPLAY INVISIBLE (-1700 1275);
FORCEADD DNS..1
(-1975 2150);
PAINT RED (-1975 2150);
FORCEPROP 2 LAST CDS_LIB mstr_misc
J 0
(-1975 2150);
DISPLAY INVISIBLE (-1975 2150);
FORCEPROP 1 LAST COMMENT_BODY TRUE
R 1
J 0
(-1900 1925);
DISPLAY 0.872340 (-1900 1925);
PAINT GREEN (-1900 1925);
DISPLAY INVISIBLE (-1900 1925);
FORCEADD DNS..1
(-4175 7075);
PAINT RED (-4175 7075);
FORCEPROP 2 LAST CDS_LIB mstr_misc
J 0
(-4175 7075);
DISPLAY INVISIBLE (-4175 7075);
FORCEPROP 1 LAST COMMENT_BODY TRUE
R 1
J 0
(-4100 6850);
DISPLAY 0.872340 (-4100 6850);
PAINT GREEN (-4100 6850);
DISPLAY INVISIBLE (-4100 6850);
FORCEADD DNS..1
(-4375 7075);
PAINT RED (-4375 7075);
FORCEPROP 2 LAST CDS_LIB mstr_misc
J 0
(-4375 7075);
DISPLAY INVISIBLE (-4375 7075);
FORCEPROP 1 LAST COMMENT_BODY TRUE
R 1
J 0
(-4300 6850);
DISPLAY 0.872340 (-4300 6850);
PAINT GREEN (-4300 6850);
DISPLAY INVISIBLE (-4300 6850);
FORCEADD DNS..1
(-4550 7075);
PAINT RED (-4550 7075);
FORCEPROP 2 LAST CDS_LIB mstr_misc
J 0
(-4550 7075);
DISPLAY INVISIBLE (-4550 7075);
FORCEPROP 1 LAST COMMENT_BODY TRUE
R 1
J 0
(-4475 6850);
DISPLAY 0.872340 (-4475 6850);
PAINT GREEN (-4475 6850);
DISPLAY INVISIBLE (-4475 6850);
FORCEADD DNS..1
(-4225 6100);
PAINT RED (-4225 6100);
FORCEPROP 2 LAST CDS_LIB mstr_misc
J 0
(-4225 6100);
DISPLAY INVISIBLE (-4225 6100);
FORCEPROP 1 LAST COMMENT_BODY TRUE
R 1
J 0
(-4150 5875);
DISPLAY 0.872340 (-4150 5875);
PAINT GREEN (-4150 5875);
DISPLAY INVISIBLE (-4150 5875);
FORCEADD DNS..1
(-4800 6100);
PAINT RED (-4800 6100);
FORCEPROP 2 LAST CDS_LIB mstr_misc
J 0
(-4800 6100);
DISPLAY INVISIBLE (-4800 6100);
FORCEPROP 1 LAST COMMENT_BODY TRUE
R 1
J 0
(-4725 5875);
DISPLAY 0.872340 (-4725 5875);
PAINT GREEN (-4725 5875);
DISPLAY INVISIBLE (-4725 5875);
FORCEADD DNS..1
(-4925 7075);
PAINT RED (-4925 7075);
FORCEPROP 2 LAST CDS_LIB mstr_misc
J 0
(-4925 7075);
DISPLAY INVISIBLE (-4925 7075);
FORCEPROP 1 LAST COMMENT_BODY TRUE
R 1
J 0
(-4850 6850);
DISPLAY 0.872340 (-4850 6850);
PAINT GREEN (-4850 6850);
DISPLAY INVISIBLE (-4850 6850);
FORCEADD QUANTA_TITLE_BLOCK_C..1
(3950 1075);
FORCEPROP 0 LAST CDS_CON_LAST_MODIFIED Thu Sep 14 16:12:42 2023
J 0
(2065 1090);
DISPLAY INVISIBLE (2065 1090);
FORCEPROP 1 LAST CUSTOM_TXT_CDS <CON_LAST_MODIFIED>
J 0
(2065 1090);
DISPLAY 0.978723 (2065 1090);
FORCEPROP 2 LAST CUSTOM_TXT_CDS <XR_PAGE_TITLE>
J 0
(-3940 6325);
DISPLAY 0.638298 (-3940 6325);
PAINT PINK (-3940 6325);
DISPLAY INVISIBLE (-3940 6325);
FORCEPROP 1 LAST CUSTOM_TXT_CDS <NAME_2>
J 0
(775 1125);
FORCEPROP 1 LAST CUSTOM_TXT_CDS <NAME_1>
J 0
(775 1250);
FORCEPROP 1 LAST CUSTOM_TXT_CDS <Q_NUMBER>
J 0
(2547 1178);
DISPLAY 1.212766 (2547 1178);
FORCEPROP 1 LAST CUSTOM_TXT_CDS <Q_PROJ>
J 0
(1568 1177);
DISPLAY 1.212766 (1568 1177);
FORCEPROP 1 LAST CUSTOM_TXT_CDS <Q_REV>
J 0
(3766 1178);
DISPLAY 1.212766 (3766 1178);
FORCEPROP 1 LAST CUSTOM_TXT_CDS <CON_PAGE_NUM> OF <CON_TOTAL_PAGES>
J 0
(3504 1093);
DISPLAY 0.978723 (3504 1093);
FORCEPROP 1 LAST Q_TITLE PVDDCR_CPU1_P1/PVDDIO_P1 VR CONTROLLER
J 0
(-5350 1125);
DISPLAY 2.446809 (-5350 1125);
PAINT GREEN (-5350 1125);
FORCEPROP 1 LAST CDS_LMAN_SYM_OUTLINE -9475,6775,100,-125
J 0
(3950 1075);
DISPLAY 0.468085 (3950 1075);
PAINT GREEN (3950 1075);
DISPLAY INVISIBLE (3950 1075);
FORCEPROP 2 LAST CDS_LIB pure_quanta
J 0
(3950 1075);
DISPLAY INVISIBLE (3950 1075);
FORCEPROP 2 LAST PAGE_BORDER TRUE
J 0
(-3940 6325);
DISPLAY 0.638298 (-3940 6325);
PAINT PINK (-3940 6325);
DISPLAY INVISIBLE (-3940 6325);
FORCEPROP 2 LAST CDS_XR_PAGE_TITLE CR-217 : @T6G_MB_LIB.T6G(SCH_1):PAGE217
J 0
(-3940 6325);
DISPLAY 0.638298 (-3940 6325);
PAINT PINK (-3940 6325);
DISPLAY INVISIBLE (-3940 6325);
FORCEPROP 1 LAST Q_DEPT BU9
J 1
(187 1124);
DISPLAY 1.957447 (187 1124);
PAINT GREEN (187 1124);
DISPLAY INVISIBLE (187 1124);
FORCEPROP 1 LAST COMMENT_BODY TRUE
J 0
(3962 1062);
DISPLAY 0.978723 (3962 1062);
PAINT GREEN (3962 1062);
DISPLAY INVISIBLE (3962 1062);
WIRE 16 -1 (-3500 1875)(-3725 1875);
WIRE 16 -1 (1025 4325)(1375 4325);
WIRE 16 -1 (1375 4325)(1375 4300);
WIRE 16 -1 (-3250 2125)(-2875 2125);
WIRE 16 -1 (-3250 2125)(-3250 2175);
WIRE 16 -1 (1025 4025)(1375 4025);
WIRE 16 -1 (1375 4025)(1375 4000);
WIRE 16 -1 (-3700 7350)(-3850 7350);
WIRE 16 -1 (-3550 5550)(-3700 5550);
WIRE 16 -1 (-3725 2100)(-3875 2100);
WIRE 16 -1 (-3300 7375)(-2975 7375);
WIRE 16 -1 (-3300 7375)(-3300 7425);
WIRE 16 -1 (-1800 1400)(-1800 1350);
WIRE 16 -1 (-1450 1350)(-1450 1425);
WIRE 16 -1 (-1725 2850)(-1475 2850);
WIRE 16 -1 (-1875 2125)(-1325 2125);
WIRE 16 -1 (-2900 3600)(-2900 3550);
WIRE 16 -1 (-2900 3600)(-3325 3600);
WIRE 16 -1 (-2875 4700)(-2875 4650);
WIRE 16 -1 (-2875 4700)(-3300 4700);
WIRE 16 -1 (850 1650)(850 1750);
WIRE 16 -1 (850 2225)(850 2325);
WIRE 16 -1 (-1950 6950)(-1375 6950);
WIRE 16 -1 (-1925 7375)(-1375 7375);
WIRE 16 -1 (475 6500)(475 6425);
WIRE 16 -1 (475 6975)(475 6900);
WIRE 16 -1 (850 6425)(850 6475);
WIRE 16 -1 (850 6950)(850 6900);
WIRE 16 -1 (-3650 4850)(-2075 4850);
WIRE 16 -1 (-3650 4700)(-3650 4850);
WIRE 16 -1 (-4700 4850)(-3650 4850);
FORCEPROP 2 LAST SIG_NAME VSENSE_VSS_SENSE_C_P1
J 2
(-3910 4860);
DISPLAY 0.489362 (-3910 4860);
WIRE 16 -1 (-1375 4850)(-2075 4850);
WIRE 16 -1 (-2075 4950)(-2075 4850);
WIRE 16 -1 (-1375 4850)(-1375 4925);
WIRE 16 -1 (-3650 4700)(-3500 4700);
WIRE 16 -1 (-1175 4925)(-1375 4925);
WIRE 16 -1 (-2625 5225)(-3650 5225);
WIRE 16 -1 (-3650 5375)(-3650 5225);
WIRE 16 -1 (-3650 5225)(-4700 5225);
FORCEPROP 2 LAST SIG_NAME VSENSE_PVDDCR_CPU1_P1_DP
J 0
(-4385 5235);
DISPLAY 0.489362 (-4385 5235);
WIRE 16 -1 (-3650 5375)(-3450 5375);
WIRE 16 -1 (-1375 4125)(-2025 4125);
FORCEPROP 2 LAST SIG_NAME VSENSE_PVDDIO_P1_VSEN1
J 0
(-1835 4135);
DISPLAY 0.489362 (-1835 4135);
FORCEPROP 2 LASTPROP $XRERR UNIQUE?
J 0
(-2075 4135);
DISPLAY 0.638298 (-2075 4135);
PAINT MONO (-2075 4135);
DISPLAY INVISIBLE (-2075 4135);
WIRE 16 -1 (-1375 4125)(-1375 4075);
WIRE 16 -1 (-2375 4125)(-2025 4125);
WIRE 16 -1 (-2025 4050)(-2025 4125);
WIRE 16 -1 (-1375 4075)(-1175 4075);
WIRE 16 -1 (175 4425)(1250 4425);
FORCEPROP 2 LAST SIG_NAME NC_PVDDCR_CPU1_P1_PWM7
J 0
(315 4435);
DISPLAY 0.489362 (315 4435);
FORCEPROP 2 LASTPROP $XRERR UNIQUE?
J 0
(1280 4425);
DISPLAY 0.638298 (1280 4425);
PAINT MONO (1280 4425);
DISPLAY INVISIBLE (1280 4425);
WIRE 17 273 (2300 6250)(3900 6250);
WIRE 17 273 (2300 6250)(2300 5200);
WIRE 17 273 (3900 6250)(3900 5200);
WIRE 17 273 (2300 5200)(3900 5200);
WIRE 16 -1 (175 6925)(325 6925);
WIRE 16 -1 (325 6925)(325 6750);
WIRE 16 -1 (325 6750)(475 6750);
FORCEPROP 2 LAST SIG_NAME PVDDCR_CPU1_P1_VCCS
J 0
(365 6760);
DISPLAY 0.489362 (365 6760);
WIRE 16 -1 (475 6750)(850 6750);
WIRE 16 -1 (475 6750)(475 6700);
WIRE 16 -1 (1475 6750)(850 6750);
WIRE 16 -1 (850 6675)(850 6750);
WIRE 17 273 (2300 7550)(3900 7550);
WIRE 17 273 (2300 7550)(2300 6275);
WIRE 17 273 (3900 7550)(3900 6275);
WIRE 17 273 (2300 6275)(3900 6275);
WIRE 16 -1 (-2675 5475)(-2675 5375);
WIRE 16 -1 (-2675 5375)(-3250 5375);
WIRE 16 -1 (175 6125)(1250 6125);
FORCEPROP 2 LAST SIG_NAME PVDDCR_CPU1_P1_IMON1
J 0
(340 6135);
DISPLAY 0.489362 (340 6135);
WIRE 16 -1 (1200 7225)(850 7225);
WIRE 16 -1 (850 7225)(475 7225);
WIRE 16 -1 (850 7150)(850 7225);
WIRE 16 -1 (475 7225)(475 7175);
WIRE 16 -1 (475 7225)(175 7225);
FORCEPROP 2 LAST SIG_NAME PVDDCR_CPU1_P1_VCC
J 0
(340 7235);
DISPLAY 0.489362 (340 7235);
FORCEPROP 2 LASTPROP $XRERR UNIQUE?
J 0
(100 7235);
DISPLAY 0.638298 (100 7235);
PAINT MONO (100 7235);
DISPLAY INVISIBLE (100 7235);
WIRE 16 -1 (-1175 6325)(-2775 6325);
FORCEPROP 2 LAST SIG_NAME SVID_PVDDCR_CPU1_P1_SVTI_R
J 0
(-1875 6335);
DISPLAY 0.489362 (-1875 6335);
FORCEPROP 2 LASTPROP $XRERR UNIQUE?
J 0
(-2115 6335);
DISPLAY 0.638298 (-2115 6335);
PAINT MONO (-2115 6335);
DISPLAY INVISIBLE (-2115 6335);
WIRE 16 -1 (-2075 6075)(-1175 6075);
FORCEPROP 2 LAST SIG_NAME SMB_CLK_PVDDCR_CPU1_P1_R
J 0
(-1910 6085);
DISPLAY 0.489362 (-1910 6085);
FORCEPROP 2 LASTPROP $XRERR UNIQUE?
J 0
(-2150 6085);
DISPLAY 0.638298 (-2150 6085);
PAINT MONO (-2150 6085);
DISPLAY INVISIBLE (-2150 6085);
WIRE 16 -1 (-2775 6775)(-1175 6775);
FORCEPROP 2 LAST SIG_NAME SVID_PVDDCR_CPU1_P1_SVC_R1
J 0
(-1935 6785);
DISPLAY 0.553191 (-1935 6785);
FORCEPROP 2 LASTPROP $XRERR UNIQUE?
J 0
(-2175 6785);
DISPLAY 0.638298 (-2175 6785);
PAINT MONO (-2175 6785);
DISPLAY INVISIBLE (-2175 6785);
WIRE 16 -1 (1225 4625)(175 4625);
FORCEPROP 2 LAST SIG_NAME PVDDCR_CPU1_P1_IMON6
J 0
(340 4635);
DISPLAY 0.489362 (340 4635);
WIRE 16 -1 (-1175 6475)(-2775 6475);
FORCEPROP 2 LAST SIG_NAME SVID_PVDDCR_CPU1_P1_SVTO_R
J 0
(-1875 6485);
DISPLAY 0.489362 (-1875 6485);
FORCEPROP 2 LASTPROP $XRERR UNIQUE?
J 0
(-2115 6485);
DISPLAY 0.638298 (-2115 6485);
PAINT MONO (-2115 6485);
DISPLAY INVISIBLE (-2115 6485);
WIRE 16 -1 (-2125 3525)(-2025 3525);
WIRE 16 -1 (-2025 3525)(-2025 3375);
FORCEPROP 2 LAST SIG_NAME PVDDCR_CPU1_P1_RESET_N_R
J 0
(-1835 3385);
DISPLAY 0.489362 (-1835 3385);
FORCEPROP 2 LASTPROP $XRERR UNIQUE?
J 0
(-2075 3385);
DISPLAY 0.638298 (-2075 3385);
PAINT MONO (-2075 3385);
DISPLAY INVISIBLE (-2075 3385);
WIRE 16 -1 (-1175 3375)(-2025 3375);
WIRE 16 -1 (-2100 3375)(-2025 3375);
WIRE 16 -1 (825 4325)(175 4325);
FORCEPROP 2 LAST SIG_NAME NC_PVDDCR_CPU1_P1_IMON7
J 0
(240 4335);
DISPLAY 0.489362 (240 4335);
FORCEPROP 2 LASTPROP $XRERR UNIQUE?
J 0
(0 4335);
DISPLAY 0.638298 (0 4335);
PAINT MONO (0 4335);
DISPLAY INVISIBLE (0 4335);
WIRE 16 -1 (825 4025)(175 4025);
FORCEPROP 2 LAST SIG_NAME NC_PVDDCR_CPU1_P1_IMON8
J 0
(215 4035);
DISPLAY 0.489362 (215 4035);
FORCEPROP 2 LASTPROP $XRERR UNIQUE?
J 0
(-25 4035);
DISPLAY 0.638298 (-25 4035);
PAINT MONO (-25 4035);
DISPLAY INVISIBLE (-25 4035);
WIRE 16 -1 (-2075 2125)(-2300 2125);
WIRE 16 -1 (-2300 2125)(-2675 2125);
WIRE 16 -1 (-2300 2125)(-2300 1975);
WIRE 16 -1 (-2300 1975)(-1175 1975);
FORCEPROP 2 LAST SIG_NAME PWRGD_PVDDIO_P1_R
J 0
(-1675 1985);
DISPLAY 0.489362 (-1675 1985);
FORCEPROP 2 LASTPROP $XRERR UNIQUE?
J 0
(-1915 1985);
DISPLAY 0.638298 (-1915 1985);
PAINT MONO (-1915 1985);
DISPLAY INVISIBLE (-1915 1985);
WIRE 16 -1 (-2675 1975)(-2300 1975);
WIRE 16 -1 (-2775 6625)(-1175 6625);
FORCEPROP 2 LAST SIG_NAME SVID_PVDDCR_CPU1_P1_SVD_R1
J 0
(-1935 6635);
DISPLAY 0.553191 (-1935 6635);
FORCEPROP 2 LASTPROP $XRERR UNIQUE?
J 0
(-2175 6635);
DISPLAY 0.638298 (-2175 6635);
PAINT MONO (-2175 6635);
DISPLAY INVISIBLE (-2175 6635);
WIRE 16 -1 (-2075 5775)(-1175 5775);
FORCEPROP 2 LAST SIG_NAME PVDDCR_CPU1_P1_SMB_ALERT_R
J 0
(-1910 5785);
DISPLAY 0.489362 (-1910 5785);
FORCEPROP 2 LASTPROP $XRERR UNIQUE?
J 0
(-2150 5785);
DISPLAY 0.638298 (-2150 5785);
PAINT MONO (-2150 5785);
DISPLAY INVISIBLE (-2150 5785);
WIRE 16 -1 (-2150 6950)(-2350 6950);
WIRE 16 -1 (-2350 7075)(-2350 6950);
WIRE 16 -1 (-2350 7075)(-1175 7075);
FORCEPROP 2 LAST SIG_NAME PVDDCR_CPU1_P1_EN_R
J 0
(-1785 7085);
DISPLAY 0.489362 (-1785 7085);
FORCEPROP 2 LASTPROP $XRERR UNIQUE?
J 0
(-2025 7085);
DISPLAY 0.638298 (-2025 7085);
PAINT MONO (-2025 7085);
DISPLAY INVISIBLE (-2025 7085);
WIRE 16 -1 (-2775 7075)(-2350 7075);
WIRE 16 -1 (-2075 5925)(-1175 5925);
FORCEPROP 2 LAST SIG_NAME SMB_DIO_PVDDCR_CPU1_P1_R
J 0
(-1910 5935);
DISPLAY 0.489362 (-1910 5935);
FORCEPROP 2 LASTPROP $XRERR UNIQUE?
J 0
(-2150 5935);
DISPLAY 0.638298 (-2150 5935);
PAINT MONO (-2150 5935);
DISPLAY INVISIBLE (-2150 5935);
WIRE 16 -1 (175 4125)(1250 4125);
FORCEPROP 2 LAST SIG_NAME NC_PVDDCR_CPU1_P1_PWM8
J 0
(340 4135);
DISPLAY 0.489362 (340 4135);
FORCEPROP 2 LASTPROP $XRERR UNIQUE?
J 0
(1280 4125);
DISPLAY 0.638298 (1280 4125);
PAINT MONO (1280 4125);
DISPLAY INVISIBLE (1280 4125);
WIRE 16 -1 (-2425 5225)(-2075 5225);
WIRE 16 -1 (-1375 5225)(-2075 5225);
FORCEPROP 2 LAST SIG_NAME VSENSE_PVDDCR_CPU1_P1_VSEN0
J 0
(-1960 5235);
DISPLAY 0.489362 (-1960 5235);
FORCEPROP 2 LASTPROP $XRERR UNIQUE?
J 0
(-2200 5235);
DISPLAY 0.638298 (-2200 5235);
PAINT MONO (-2200 5235);
DISPLAY INVISIBLE (-2200 5235);
WIRE 16 -1 (-2075 5150)(-2075 5225);
WIRE 16 -1 (-1375 5225)(-1375 5175);
WIRE 16 -1 (-1375 5175)(-1175 5175);
WIRE 16 -1 (175 3225)(1250 3225);
FORCEPROP 2 LAST SIG_NAME PVDDIO_P1_PWM2
J 0
(340 3235);
DISPLAY 0.489362 (340 3235);
WIRE 16 -1 (-2125 7375)(-2350 7375);
WIRE 16 -1 (-2350 7225)(-2350 7375);
WIRE 16 -1 (-2350 7375)(-2775 7375);
WIRE 16 -1 (-2350 7225)(-1175 7225);
FORCEPROP 2 LAST SIG_NAME PWRGD_PVDDCR_CPU1_P1_R
J 0
(-1785 7235);
DISPLAY 0.489362 (-1785 7235);
FORCEPROP 2 LASTPROP $XRERR UNIQUE?
J 0
(-2025 7235);
DISPLAY 0.638298 (-2025 7235);
PAINT MONO (-2025 7235);
DISPLAY INVISIBLE (-2025 7235);
WIRE 16 -1 (-2350 7225)(-2775 7225);
WIRE 16 -1 (175 4725)(1250 4725);
FORCEPROP 0 LAST SIG_NAME PVDDCR_CPU1_P1_PWM6
J 0
(340 4735);
DISPLAY 0.489362 (340 4735);
WIRE 16 -1 (-3300 1875)(-3050 1875);
WIRE 16 -1 (-2600 1875)(-3050 1875);
WIRE 16 -1 (-3050 1800)(-3050 1875);
WIRE 16 -1 (-1175 1875)(-2600 1875);
FORCEPROP 2 LAST SIG_NAME PVDDCR_CPU1_P1_VMON
J 0
(-1675 1885);
DISPLAY 0.489362 (-1675 1885);
FORCEPROP 2 LASTPROP $XRERR UNIQUE?
J 0
(-1915 1885);
DISPLAY 0.638298 (-1915 1885);
PAINT MONO (-1915 1885);
DISPLAY INVISIBLE (-1915 1885);
WIRE 16 -1 (-2600 1825)(-2600 1875);
WIRE 16 -1 (-1975 1700)(-1800 1700);
WIRE 16 -1 (-1800 1700)(-1450 1700);
WIRE 16 -1 (-1800 1600)(-1800 1700);
WIRE 16 -1 (-1450 1625)(-1450 1700);
WIRE 16 -1 (-1450 1700)(-1450 1775);
FORCEPROP 2 LAST SIG_NAME PVDDCR_CPU1_P1_VINSEN
J 0
(-1610 1800);
DISPLAY 0.489362 (-1610 1800);
FORCEPROP 2 LASTPROP $XRERR UNIQUE?
J 0
(-1850 1800);
DISPLAY 0.638298 (-1850 1800);
PAINT MONO (-1850 1800);
DISPLAY INVISIBLE (-1850 1800);
WIRE 16 -1 (-1175 1775)(-1450 1775);
WIRE 16 -1 (1400 2025)(850 2025);
FORCEPROP 2 LAST SIG_NAME PVDDCR_CPU1_P1_TEMP0
J 0
(465 2035);
DISPLAY 0.489362 (465 2035);
WIRE 16 -1 (850 2025)(850 1950);
WIRE 16 -1 (850 2025)(175 2025);
WIRE 16 -1 (-1925 2850)(-2225 2850);
WIRE 16 -1 (-2225 2850)(-2225 2975);
WIRE 16 -1 (-2225 2850)(-2375 2850);
WIRE 16 -1 (-2375 2850)(-2375 2875);
WIRE 16 -1 (-1175 2975)(-2225 2975);
WIRE 16 -1 (-2225 3100)(-2225 2975);
WIRE 16 -1 (-1650 3100)(-2225 3100);
WIRE 16 -1 (-3650 3600)(-3525 3600);
WIRE 16 -1 (-3650 3600)(-3650 3750);
WIRE 16 -1 (-3650 3750)(-2025 3750);
WIRE 16 -1 (-4700 3750)(-3650 3750);
FORCEPROP 2 LAST SIG_NAME VSENSE_VSS_SENSE_B_P1
J 0
(-4285 3760);
DISPLAY 0.489362 (-4285 3760);
WIRE 16 -1 (-1375 3750)(-2025 3750);
WIRE 16 -1 (-2025 3850)(-2025 3750);
WIRE 16 -1 (-1375 3750)(-1375 3825);
WIRE 16 -1 (-1175 3825)(-1375 3825);
WIRE 16 -1 (1250 3125)(175 3125);
FORCEPROP 2 LAST SIG_NAME PVDDIO_P1_IMON2
J 0
(340 3135);
DISPLAY 0.489362 (340 3135);
WIRE 16 -1 (175 6225)(1250 6225);
FORCEPROP 2 LAST SIG_NAME PVDDCR_CPU1_P1_PWM1
J 0
(340 6235);
DISPLAY 0.489362 (340 6235);
WIRE 16 -1 (175 3825)(1250 3825);
FORCEPROP 2 LAST SIG_NAME PVDDIO_P1_PWM4
J 0
(340 3835);
DISPLAY 0.489362 (340 3835);
WIRE 16 -1 (1250 3725)(175 3725);
FORCEPROP 2 LAST SIG_NAME PVDDIO_P1_IMON4
J 0
(340 3735);
DISPLAY 0.489362 (340 3735);
WIRE 16 -1 (175 3525)(1250 3525);
FORCEPROP 0 LAST SIG_NAME PVDDIO_P1_PWM3
J 0
(340 3535);
DISPLAY 0.489362 (340 3535);
WIRE 16 -1 (1250 3425)(175 3425);
FORCEPROP 2 LAST SIG_NAME PVDDIO_P1_IMON3
J 0
(340 3435);
DISPLAY 0.489362 (340 3435);
WIRE 16 -1 (-1450 3100)(-1300 3100);
WIRE 16 -1 (-1300 3100)(-1300 3225);
WIRE 16 -1 (-1175 3225)(-1300 3225);
FORCEPROP 2 LAST SIG_NAME PVDDCR_CPU1_P1_OCP_N_R
J 0
(-1785 3250);
DISPLAY 0.489362 (-1785 3250);
FORCEPROP 2 LASTPROP $XRERR UNIQUE?
J 0
(-2025 3250);
DISPLAY 0.638298 (-2025 3250);
PAINT MONO (-2025 3250);
DISPLAY INVISIBLE (-2025 3250);
WIRE 16 -1 (-2100 3225)(-1300 3225);
WIRE 16 -1 (-1250 1675)(-1175 1675);
WIRE 16 -1 (-1250 1600)(-1250 1675);
WIRE 16 -1 (-3300 2625)(-3300 2675);
WIRE 16 -1 (-2150 2675)(-3300 2675);
WIRE 16 -1 (-3300 2675)(-3300 2750);
WIRE 16 -1 (-2150 2675)(-2150 2475);
WIRE 16 -1 (-1175 2475)(-2150 2475);
FORCEPROP 2 LAST SIG_NAME PVDDCR_CPU1_P1_EN1_ADDR_CFG
J 0
(-1960 2485);
DISPLAY 0.489362 (-1960 2485);
FORCEPROP 2 LASTPROP $XRERR UNIQUE?
J 0
(-2200 2485);
DISPLAY 0.638298 (-2200 2485);
PAINT MONO (-2200 2485);
DISPLAY INVISIBLE (-2200 2485);
WIRE 16 -1 (850 2625)(1400 2625);
WIRE 16 -1 (850 2625)(850 2525);
WIRE 16 -1 (850 2625)(400 2625);
FORCEPROP 2 LAST SIG_NAME PVDDIO_P1_TEMP1
J 0
(490 2635);
DISPLAY 0.489362 (490 2635);
WIRE 16 -1 (400 2625)(400 2325);
WIRE 16 -1 (400 2325)(175 2325);
WIRE 16 -1 (175 2925)(1250 2925);
FORCEPROP 2 LAST SIG_NAME PVDDIO_P1_PWM1
J 0
(340 2935);
DISPLAY 0.489362 (340 2935);
WIRE 16 -1 (1250 2825)(175 2825);
FORCEPROP 2 LAST SIG_NAME PVDDIO_P1_IMON1
J 0
(340 2835);
DISPLAY 0.489362 (340 2835);
WIRE 16 -1 (175 5025)(1250 5025);
FORCEPROP 0 LAST SIG_NAME PVDDCR_CPU1_P1_PWM5
J 0
(340 5035);
DISPLAY 0.489362 (340 5035);
WIRE 16 -1 (175 4925)(1250 4925);
FORCEPROP 2 LAST SIG_NAME PVDDCR_CPU1_P1_IMON5
J 0
(340 4935);
DISPLAY 0.489362 (340 4935);
WIRE 16 -1 (175 5325)(1250 5325);
FORCEPROP 2 LAST SIG_NAME PVDDCR_CPU1_P1_PWM4
J 0
(340 5335);
DISPLAY 0.489362 (340 5335);
WIRE 16 -1 (175 5225)(1250 5225);
FORCEPROP 2 LAST SIG_NAME PVDDCR_CPU1_P1_IMON4
J 0
(340 5235);
DISPLAY 0.489362 (340 5235);
WIRE 16 -1 (175 5625)(1250 5625);
FORCEPROP 2 LAST SIG_NAME PVDDCR_CPU1_P1_PWM3
J 0
(340 5635);
DISPLAY 0.489362 (340 5635);
WIRE 16 -1 (175 5525)(1250 5525);
FORCEPROP 2 LAST SIG_NAME PVDDCR_CPU1_P1_IMON3
J 0
(340 5535);
DISPLAY 0.489362 (340 5535);
WIRE 16 -1 (175 5925)(1275 5925);
FORCEPROP 2 LAST SIG_NAME PVDDCR_CPU1_P1_PWM2
J 0
(340 5935);
DISPLAY 0.489362 (340 5935);
WIRE 16 -1 (175 5825)(1275 5825);
FORCEPROP 2 LAST SIG_NAME PVDDCR_CPU1_P1_IMON2
J 0
(340 5835);
DISPLAY 0.489362 (340 5835);
WIRE 16 -1 (-4575 7000)(-4575 6475);
WIRE 16 -1 (-4575 6475)(-2975 6475);
FORCEPROP 2 LAST SIG_NAME SVID_PVDDCR_CPU1_P1_SVTO
J 0
(-3785 6485);
DISPLAY 0.489362 (-3785 6485);
WIRE 16 -1 (-4650 6475)(-4575 6475);
WIRE 16 -1 (-4825 6475)(-4650 6475);
WIRE 16 -1 (-4650 6200)(-4650 6475);
WIRE 16 -1 (-4825 6225)(-4825 6475);
WIRE 16 -1 (-4975 6475)(-4825 6475);
WIRE 16 -1 (-4400 7000)(-4400 6625);
WIRE 16 -1 (-4400 6625)(-2975 6625);
FORCEPROP 2 LAST SIG_NAME SVID_PVDDCR_CPU1_P1_SVD_R
J 0
(-3810 6660);
DISPLAY 0.489362 (-3810 6660);
WIRE 16 -1 (-4450 6625)(-4400 6625);
WIRE 16 -1 (-4450 6225)(-4450 6625);
WIRE 16 -1 (-4975 6625)(-4450 6625);
WIRE 16 -1 (-4200 7000)(-4200 6775);
WIRE 16 -1 (-4200 6775)(-2975 6775);
FORCEPROP 2 LAST SIG_NAME SVID_PVDDCR_CPU1_P1_SVC_R
J 0
(-3810 6785);
DISPLAY 0.489362 (-3810 6785);
WIRE 16 -1 (-4250 6775)(-4200 6775);
WIRE 16 -1 (-4250 6225)(-4250 6775);
WIRE 16 -1 (-4975 6775)(-4250 6775);
WIRE 16 -1 (-3100 6075)(-2275 6075);
FORCEPROP 2 LAST SIG_NAME SMB_SCM_2_R1_SCL
J 0
(-2885 6085);
DISPLAY 0.489362 (-2885 6085);
WIRE 16 -1 (-4950 7000)(-4950 6325);
WIRE 16 -1 (-4950 6325)(-2975 6325);
FORCEPROP 2 LAST SIG_NAME SVID_PVDDCR_CPU1_P1_SVTI
J 0
(-3785 6350);
DISPLAY 0.489362 (-3785 6350);
FORCEPROP 2 LASTPROP $XRERR UNIQUE?
J 0
(-4025 6350);
DISPLAY 0.638298 (-4025 6350);
PAINT MONO (-4025 6350);
DISPLAY INVISIBLE (-4025 6350);
WIRE 16 -1 (-5000 6325)(-4950 6325);
WIRE 16 -1 (-5000 6325)(-5000 6225);
WIRE 16 -1 (1825 7300)(1825 7225);
WIRE 16 -1 (1825 7225)(1400 7225);
WIRE 16 -1 (-3300 3350)(-3300 3425);
WIRE 16 -1 (-3300 3425)(-4000 3425);
WIRE 16 -1 (-4000 3350)(-4000 3425);
WIRE 16 -1 (-4000 3425)(-4000 3450);
WIRE 16 -1 (-4825 6025)(-4825 5825);
WIRE 16 -1 (-4825 5825)(-4650 5825);
WIRE 16 -1 (-5000 5825)(-4825 5825);
WIRE 16 -1 (-5000 6025)(-5000 5825);
WIRE 16 -1 (-5000 5825)(-5000 5725);
WIRE 16 -1 (-4650 5825)(-4450 5825);
WIRE 16 -1 (-4650 6000)(-4650 5825);
WIRE 16 -1 (-4450 5825)(-4250 5825);
WIRE 16 -1 (-4450 6025)(-4450 5825);
WIRE 16 -1 (-4250 5825)(-4250 6025);
WIRE 16 -1 (-4575 7350)(-4400 7350);
WIRE 16 -1 (-4575 7350)(-4575 7200);
WIRE 16 -1 (-4950 7350)(-4575 7350);
WIRE 16 -1 (-4400 7350)(-4200 7350);
WIRE 16 -1 (-4400 7200)(-4400 7350);
WIRE 16 -1 (-4200 7350)(-4200 7200);
WIRE 16 -1 (-4950 7200)(-4950 7350);
WIRE 16 -1 (-4950 7350)(-4950 7400);
WIRE 16 -1 (-4550 2225)(-4550 2200);
WIRE 16 -1 (-4550 2200)(-4325 2200);
FORCEPROP 0 LAST VOLTAGE 0
J 0
(-4512 2200);
DISPLAY INVISIBLE (-4512 2200);
WIRE 16 -1 (-4325 2200)(-4325 2300);
WIRE 16 -1 (-4325 2150)(-4325 2200);
WIRE 16 -1 (-3050 1600)(-3050 1500);
WIRE 16 -1 (-3050 1500)(-2600 1500);
WIRE 16 -1 (-2600 1625)(-2600 1500);
WIRE 16 -1 (-2600 1500)(-2600 1450);
WIRE 16 -1 (-2325 1700)(-2175 1700);
WIRE 16 -1 (-2325 1725)(-2325 1700);
WIRE 16 -1 (-2675 3525)(-2325 3525);
WIRE 16 -1 (-2675 3600)(-2675 3525);
WIRE 16 -1 (-2875 4375)(-2875 4275);
WIRE 16 -1 (-2875 4275)(-3300 4275);
WIRE 16 -1 (-3300 2400)(-3300 2425);
WIRE 16 -1 (-4000 2400)(-3300 2400);
WIRE 16 -1 (-4000 2475)(-4000 2400);
WIRE 16 -1 (-4000 2400)(-4000 2325);
WIRE 16 -1 (-2825 3375)(-2300 3375);
FORCEPROP 2 LAST SIG_NAME PVDDCR_CPU1_P1_RESET_N
J 0
(-2810 3385);
DISPLAY 0.489362 (-2810 3385);
WIRE 17 273 (-5250 1650)(-4050 1650);
WIRE 17 273 (-5250 1650)(-5250 1250);
WIRE 17 273 (-4050 1650)(-4050 1250);
WIRE 17 273 (-5250 1250)(-4050 1250);
WIRE 16 -1 (-3100 5775)(-2925 5775);
FORCEPROP 2 LAST SIG_NAME PVDDCR_CPU1_P1_SMB_ALERT
J 0
(-3085 5785);
DISPLAY 0.489362 (-3085 5785);
WIRE 16 -1 (-2925 5775)(-2275 5775);
WIRE 16 -1 (-2925 5550)(-2925 5775);
WIRE 16 -1 (-2925 5550)(-3350 5550);
WIRE 16 -1 (-3100 5925)(-2275 5925);
FORCEPROP 2 LAST SIG_NAME SMB_SCM_2_R1_SDA
J 0
(-2885 5935);
DISPLAY 0.489362 (-2885 5935);
WIRE 16 -1 (-3150 2100)(-3525 2100);
WIRE 16 -1 (-3150 2100)(-3150 2025);
WIRE 16 -1 (-3100 2025)(-3150 2025);
WIRE 16 -1 (-3150 2025)(-3875 2025);
FORCEPROP 2 LAST SIG_NAME PWRGD_PVDDIO_P1
J 0
(-3860 2035);
DISPLAY 0.489362 (-3860 2035);
WIRE 16 -1 (-3100 1975)(-3100 2025);
WIRE 16 -1 (-2875 1975)(-3100 1975);
WIRE 16 -1 (-4550 2575)(-4325 2575);
FORCEPROP 2 LAST SIG_NAME PVDDIO_P1_EN_R
J 0
(-4535 2585);
DISPLAY 0.489362 (-4535 2585);
FORCEPROP 2 LASTPROP $XRERR UNIQUE?
J 0
(-4775 2585);
DISPLAY 0.638298 (-4775 2585);
PAINT MONO (-4775 2585);
DISPLAY INVISIBLE (-4775 2585);
WIRE 16 -1 (-4600 2575)(-4550 2575);
WIRE 16 -1 (-4550 2575)(-4550 2425);
WIRE 16 -1 (-4150 2575)(-4325 2575);
WIRE 16 -1 (-4325 2575)(-4325 2500);
WIRE 16 -1 (-4700 4125)(-3650 4125);
FORCEPROP 2 LAST SIG_NAME VSENSE_PVDDIO_P1_DP
J 0
(-4310 4135);
DISPLAY 0.489362 (-4310 4135);
WIRE 16 -1 (-2575 4125)(-3650 4125);
WIRE 16 -1 (-3650 4125)(-3650 4275);
WIRE 16 -1 (-3650 4275)(-3500 4275);
WIRE 17 273 (-4950 4775)(-4950 5325);
WIRE 17 273 (-4950 4775)(-4600 4775);
WIRE 17 273 (-4950 5325)(-4600 5325);
WIRE 17 273 (-4600 5325)(-4600 4775);
WIRE 16 -1 (-2825 3225)(-2300 3225);
FORCEPROP 2 LAST SIG_NAME PVDDCR_CPU1_P1_OCP_N
J 0
(-2810 3235);
DISPLAY 0.489362 (-2810 3235);
WIRE 17 273 (-4975 3675)(-4975 4225);
WIRE 17 273 (-4975 3675)(-4650 3675);
WIRE 17 273 (-4975 4225)(-4650 4225);
WIRE 17 273 (-4650 4225)(-4650 3675);
WIRE 16 -1 (-3600 3050)(-4000 3050);
FORCEPROP 2 LAST SIG_NAME PVDDIO_P1_EN_G
J 0
(-3960 3025);
DISPLAY 0.489362 (-3960 3025);
FORCEPROP 2 LASTPROP $XRERR UNIQUE?
J 0
(-4200 3025);
DISPLAY 0.638298 (-4200 3025);
PAINT MONO (-4200 3025);
DISPLAY INVISIBLE (-4200 3025);
WIRE 16 -1 (-4000 3150)(-4000 3050);
WIRE 16 -1 (-4000 2775)(-4000 3050);
WIRE 16 -1 (-5150 2575)(-4800 2575);
FORCEPROP 2 LAST SIG_NAME PVDDIO_P1_EN
J 0
(-5160 2585);
DISPLAY 0.489362 (-5160 2585);
WIRE 16 -1 (-3125 7225)(-2975 7225);
WIRE 16 -1 (-3125 7225)(-3125 7350);
WIRE 16 -1 (-3600 7225)(-3125 7225);
FORCEPROP 2 LAST SIG_NAME PWRGD_PVDDCR_CPU1_P1
J 0
(-3610 7235);
DISPLAY 0.489362 (-3610 7235);
WIRE 16 -1 (-3125 7350)(-3500 7350);
WIRE 16 -1 (-3600 7075)(-2975 7075);
FORCEPROP 2 LAST SIG_NAME FM_PVDDCR_CPU1_P1_EN
J 0
(-3610 7085);
DISPLAY 0.489362 (-3610 7085);
DOT 1 (-4200 6775);
DOT 1 (-4400 6625);
DOT 1 (-2350 7075);
DOT 1 (-2075 4850);
CIRCLE (-2550 5200)(-2390 5200);
PAINT YELLOW (-2550 5200);
DOT 1 (-4650 6475);
DOT 1 (-4825 5825);
DOT 1 (-3150 2025);
DOT 1 (-2925 5775);
DOT 1 (-3125 7225);
DOT 1 (-4575 7350);
DOT 1 (-4400 7350);
DOT 1 (-2350 7375);
DOT 1 (-3050 1875);
DOT 1 (850 7225);
DOT 1 (475 7225);
DOT 1 (850 6750);
DOT 1 (475 6750);
DOT 1 (-2350 7225);
DOT 1 (850 2625);
DOT 1 (850 2025);
DOT 1 (-1300 3225);
DOT 1 (-2025 4125);
DOT 1 (-2025 3750);
DOT 1 (-2025 3375);
DOT 1 (-2225 2975);
DOT 1 (-1450 1700);
DOT 1 (-1800 1700);
DOT 1 (-2225 2850);
DOT 1 (-2300 1975);
DOT 1 (-2300 2125);
DOT 1 (-2600 1875);
DOT 1 (-2600 1500);
DOT 1 (-4950 7350);
DOT 1 (-3650 5225);
DOT 1 (-4250 6775);
DOT 1 (-4450 6625);
DOT 1 (-4575 6475);
DOT 1 (-4825 6475);
DOT 1 (-4950 6325);
DOT 1 (-4650 5825);
DOT 1 (-5000 5825);
DOT 1 (-3650 4850);
DOT 1 (-3650 4125);
DOT 1 (-3650 3750);
DOT 1 (-4000 3425);
DOT 1 (-4000 3050);
DOT 1 (-3300 2675);
DOT 1 (-4325 2575);
DOT 1 (-4550 2575);
DOT 1 (-4325 2200);
DOT 1 (-4000 2400);
DOT 1 (-2075 5225);
CIRCLE (-2500 4175)(-2340 4175);
PAINT YELLOW (-2500 4175);
DOT 1 (-4450 5825);
FORCENOTE
ADDRESS(7-BIT)
(-4950 1575) 0;
DISPLAY LEFT (-4950 1575);
DISPLAY 0.808511 (-4950 1575);
PAINT WHITE (-4950 1575);
FORCENOTE
CONFIG
(-4375 1575) 0;
DISPLAY LEFT (-4375 1575);
DISPLAY 0.808511 (-4375 1575);
PAINT WHITE (-4375 1575);
FORCENOTE
1/9.53K
(-4375 1475) 0;
DISPLAY LEFT (-4375 1475);
DISPLAY 0.638298 (-4375 1475);
PAINT WHITE (-4375 1475);
FORCENOTE
/42.2K
(-4375 1325) 0;
DISPLAY LEFT (-4375 1325);
DISPLAY 0.638298 (-4375 1325);
PAINT WHITE (-4375 1325);
FORCENOTE
0X4C
(-4725 1325) 0;
DISPLAY LEFT (-4725 1325);
DISPLAY 0.638298 (-4725 1325);
PAINT WHITE (-4725 1325);
FORCENOTE
PC366=CH5103KEB01
(2250 2500) 0;
DISPLAY LEFT (2250 2500);
DISPLAY 1.021277 (2250 2500);
PAINT WHITE (2250 2500);
FORCENOTE
PR244 = CS22002FB07
(2250 3775) 0;
DISPLAY LEFT (2250 3775);
DISPLAY 1.021277 (2250 3775);
PAINT WHITE (2250 3775);
FORCENOTE
PC366 = CH5103KEB01
(2250 3700) 0;
DISPLAY LEFT (2250 3700);
DISPLAY 1.021277 (2250 3700);
PAINT WHITE (2250 3700);
FORCENOTE
PC358,PC361 = CH12206KB14
(2250 3550) 0;
DISPLAY LEFT (2250 3550);
DISPLAY 1.021277 (2250 3550);
PAINT WHITE (2250 3550);
FORCENOTE
PC357 = CH3104J1B00
(2250 3475) 0;
DISPLAY LEFT (2250 3475);
DISPLAY 1.021277 (2250 3475);
PAINT WHITE (2250 3475);
FORCENOTE
3RD SOURCE:MPS BOM
(2250 3250) 0;
DISPLAY LEFT (2250 3250);
DISPLAY 1.276596 (2250 3250);
PAINT WHITE (2250 3250);
FORCENOTE
PU34 = TBD/MP2857GQKT-001B-Z
(2250 3175) 0;
DISPLAY LEFT (2250 3175);
DISPLAY 1.021277 (2250 3175);
PAINT WHITE (2250 3175);
FORCENOTE
PC358,PC361,PR230,PC357=EMPTY
(2250 3100) 0;
DISPLAY LEFT (2250 3100);
DISPLAY 1.021277 (2250 3100);
PAINT WHITE (2250 3100);
FORCENOTE
PC364 = CH21006JB10
(2250 2575) 0;
DISPLAY LEFT (2250 2575);
DISPLAY 1.021277 (2250 2575);
PAINT WHITE (2250 2575);
FORCENOTE
PC367,PC368 = CH31004KB17
(2250 2650) 0;
DISPLAY LEFT (2250 2650);
DISPLAY 1.021277 (2250 2650);
PAINT WHITE (2250 2650);
FORCENOTE
PR603 = CS24992FB07
(2250 2725) 0;
DISPLAY LEFT (2250 2725);
DISPLAY 1.021277 (2250 2725);
PAINT WHITE (2250 2725);
FORCENOTE
PR251 = CS37502FB05
(2250 2800) 0;
DISPLAY LEFT (2250 2800);
DISPLAY 1.021277 (2250 2800);
PAINT WHITE (2250 2800);
FORCENOTE
PR244 = CS34222FB06
(2250 2875) 0;
DISPLAY LEFT (2250 2875);
DISPLAY 1.021277 (2250 2875);
PAINT WHITE (2250 2875);
FORCENOTE
PR231 = CS00002JB13
(2250 3025) 0;
DISPLAY LEFT (2250 3025);
DISPLAY 1.021277 (2250 3025);
PAINT WHITE (2250 3025);
FORCENOTE
PR533,PR12=EMPTY
(2250 2950) 0;
DISPLAY LEFT (2250 2950);
DISPLAY 1.021277 (2250 2950);
PAINT WHITE (2250 2950);
FORCENOTE
PC367,PC368 = CH11006JB00
(2250 3625) 0;
DISPLAY LEFT (2250 3625);
DISPLAY 1.021277 (2250 3625);
PAINT WHITE (2250 3625);
FORCENOTE
PVDDCR_CPU1_P1 SPECFICATION
(2325 7472) 0;
DISPLAY LEFT (2325 7472);
DISPLAY 1.170213 (2325 7472);
PAINT WHITE (2325 7472);
FORCENOTE
DEFAULT POWER-ON VID=0.9V
(2325 7350) 0;
DISPLAY LEFT (2325 7350);
DISPLAY 0.936170 (2325 7350);
PAINT WHITE (2325 7350);
FORCENOTE
MAX LOAD RELEASE=200A
(2325 6675) 0;
DISPLAY LEFT (2325 6675);
DISPLAY 0.936170 (2325 6675);
PAINT WHITE (2325 6675);
FORCENOTE
MIN AC=VID-EDC*LL-110MV
(2325 7050) 0;
DISPLAY LEFT (2325 7050);
DISPLAY 0.936170 (2325 7050);
PAINT WHITE (2325 7050);
FORCENOTE
WORK FREQUENCY=600KHZ
(2325 6525) 0;
DISPLAY LEFT (2325 6525);
DISPLAY 0.936170 (2325 6525);
PAINT WHITE (2325 6525);
FORCENOTE
EFFICIENCY > 90% @TDC
(2325 6450) 0;
DISPLAY LEFT (2325 6450);
DISPLAY 0.936170 (2325 6450);
PAINT WHITE (2325 6450);
FORCENOTE
VID=0.55-1.5V
(2325 7275) 0;
DISPLAY LEFT (2325 7275);
DISPLAY 0.936170 (2325 7275);
PAINT WHITE (2325 7275);
FORCENOTE
DC=+/-20MV
(2325 7200) 0;
DISPLAY LEFT (2325 7200);
DISPLAY 0.936170 (2325 7200);
PAINT WHITE (2325 7200);
FORCENOTE
MAX AC=VID+200MV
(2325 7125) 0;
DISPLAY LEFT (2325 7125);
DISPLAY 0.936170 (2325 7125);
PAINT WHITE (2325 7125);
FORCENOTE
TDC=175A
(2325 6975) 0;
DISPLAY LEFT (2325 6975);
DISPLAY 0.936170 (2325 6975);
PAINT WHITE (2325 6975);
FORCENOTE
MAX LOAD STEP=200A
(2325 6750) 0;
DISPLAY LEFT (2325 6750);
DISPLAY 0.936170 (2325 6750);
PAINT WHITE (2325 6750);
FORCENOTE
OCP=276A (EDC*1.2)
(2325 6825) 0;
DISPLAY LEFT (2325 6825);
DISPLAY 0.936170 (2325 6825);
PAINT WHITE (2325 6825);
FORCENOTE
EDC=230A
(2325 6900) 0;
DISPLAY LEFT (2325 6900);
DISPLAY 0.936170 (2325 6900);
PAINT WHITE (2325 6900);
FORCENOTE
LOAD-LINE=0.4MOHM
(2325 6600) 0;
DISPLAY LEFT (2325 6600);
DISPLAY 0.936170 (2325 6600);
PAINT WHITE (2325 6600);
FORCENOTE
TDC=120A
(2325 5825) 0;
DISPLAY LEFT (2325 5825);
DISPLAY 0.936170 (2325 5825);
PAINT WHITE (2325 5825);
FORCENOTE
TRACE SPACING = 5MIL
(-5000 4525) 0;
DISPLAY LEFT (-5000 4525);
DISPLAY 1.021277 (-5000 4525);
PAINT WHITE (-5000 4525);
FORCENOTE
TRACE WIDTH = 10MIL
(-5000 4600) 0;
DISPLAY LEFT (-5000 4600);
DISPLAY 1.021277 (-5000 4600);
PAINT WHITE (-5000 4600);
FORCENOTE
DIFFERENTIAL PAIR
(-5000 4675) 0;
DISPLAY LEFT (-5000 4675);
DISPLAY 1.021277 (-5000 4675);
PAINT WHITE (-5000 4675);
FORCENOTE
0X74
(-4725 1475) 0;
DISPLAY LEFT (-4725 1475);
DISPLAY 0.638298 (-4725 1475);
PAINT WHITE (-4725 1475);
FORCENOTE
RENESAS
(-5175 1475) 0;
DISPLAY LEFT (-5175 1475);
DISPLAY 0.638298 (-5175 1475);
PAINT WHITE (-5175 1475);
FORCENOTE
VR
(-5175 1575) 0;
DISPLAY LEFT (-5175 1575);
DISPLAY 0.808511 (-5175 1575);
PAINT WHITE (-5175 1575);
FORCENOTE
MPS
(-5175 1325) 0;
DISPLAY LEFT (-5175 1325);
DISPLAY 0.638298 (-5175 1325);
PAINT WHITE (-5175 1325);
FORCENOTE
DIFFERENTIAL PAIR
(-5200 3575) 0;
DISPLAY LEFT (-5200 3575);
DISPLAY 1.021277 (-5200 3575);
PAINT WHITE (-5200 3575);
FORCENOTE
TRACE WIDTH = 10MIL
(-5200 3500) 0;
DISPLAY LEFT (-5200 3500);
DISPLAY 1.021277 (-5200 3500);
PAINT WHITE (-5200 3500);
FORCENOTE
TRACE SPACING = 5MIL
(-5200 3425) 0;
DISPLAY LEFT (-5200 3425);
DISPLAY 1.021277 (-5200 3425);
PAINT WHITE (-5200 3425);
FORCENOTE
/2K
(-4375 1400) 0;
DISPLAY LEFT (-4375 1400);
DISPLAY 0.638298 (-4375 1400);
PAINT WHITE (-4375 1400);
FORCENOTE
0X4C
(-4725 1400) 0;
DISPLAY LEFT (-4725 1400);
DISPLAY 0.638298 (-4725 1400);
PAINT WHITE (-4725 1400);
FORCENOTE
INFINEON
(-5175 1400) 0;
DISPLAY LEFT (-5175 1400);
DISPLAY 0.638298 (-5175 1400);
PAINT WHITE (-5175 1400);
FORCENOTE
PR245,PR246 = CS01002FB07
(2250 3850) 0;
DISPLAY LEFT (2250 3850);
DISPLAY 1.021277 (2250 3850);
PAINT WHITE (2250 3850);
FORCENOTE
2ND SOURCE:INFENEON BOM
(2250 4225) 0;
DISPLAY LEFT (2250 4225);
DISPLAY 1.276596 (2250 4225);
PAINT WHITE (2250 4225);
FORCENOTE
PU34 = TBD/XDPE192C3B
(2250 4150) 0;
DISPLAY LEFT (2250 4150);
DISPLAY 1.021277 (2250 4150);
PAINT WHITE (2250 4150);
FORCENOTE
PR230 = CS25362FB02
(2250 4075) 0;
DISPLAY LEFT (2250 4075);
DISPLAY 1.021277 (2250 4075);
PAINT WHITE (2250 4075);
FORCENOTE
PR231 = CS21002FB06
(2250 4000) 0;
DISPLAY LEFT (2250 4000);
DISPLAY 1.021277 (2250 4000);
PAINT WHITE (2250 4000);
FORCENOTE
PR12,PR533 = EMPTY
(2250 3925) 0;
DISPLAY LEFT (2250 3925);
DISPLAY 1.021277 (2250 3925);
PAINT WHITE (2250 3925);
FORCENOTE
NOTE: 0 OHM CHECK
(-5225 5600) 0;
DISPLAY LEFT (-5225 5600);
DISPLAY 0.936170 (-5225 5600);
PAINT WHITE (-5225 5600);
FORCENOTE
VID=0.9-1.2V
(2325 5975) 0;
DISPLAY LEFT (2325 5975);
DISPLAY 0.936170 (2325 5975);
PAINT WHITE (2325 5975);
FORCENOTE
PVDDIO_P1 SPECFICATION
(2325 6175) 0;
DISPLAY LEFT (2325 6175);
DISPLAY 1.276596 (2325 6175);
PAINT WHITE (2325 6175);
FORCENOTE
SVI3 ADDRESS=PORT1 (0X1)
(2325 6375) 0;
DISPLAY LEFT (2325 6375);
DISPLAY 0.936170 (2325 6375);
PAINT WHITE (2325 6375);
FORCENOTE
EDC=140A
(2325 5750) 0;
DISPLAY LEFT (2325 5750);
DISPLAY 0.936170 (2325 5750);
PAINT WHITE (2325 5750);
FORCENOTE
WORK FREQUENCY=600KHZ
(2325 5450) 0;
DISPLAY LEFT (2325 5450);
DISPLAY 0.936170 (2325 5450);
PAINT WHITE (2325 5450);
FORCENOTE
EFFICIENCY > 90% @TDC
(2325 5375) 0;
DISPLAY LEFT (2325 5375);
DISPLAY 0.936170 (2325 5375);
PAINT WHITE (2325 5375);
FORCENOTE
SVI3 ADDRESS=PORT1 (0X2)
(2325 5300) 0;
DISPLAY LEFT (2325 5300);
DISPLAY 0.936170 (2325 5300);
PAINT WHITE (2325 5300);
FORCENOTE
IRM REV1.09
(2325 6300) 0;
DISPLAY LEFT (2325 6300);
DISPLAY 0.936170 (2325 6300);
PAINT WHITE (2325 6300);
FORCENOTE
MAX LOAD RELEASE=37A
(2325 5525) 0;
DISPLAY LEFT (2325 5525);
DISPLAY 0.936170 (2325 5525);
PAINT WHITE (2325 5525);
FORCENOTE
MAX LOAD STEP=44A
(2325 5600) 0;
DISPLAY LEFT (2325 5600);
DISPLAY 0.936170 (2325 5600);
PAINT WHITE (2325 5600);
FORCENOTE
OCP=168A (EDC*1.2)
(2325 5675) 0;
DISPLAY LEFT (2325 5675);
DISPLAY 0.936170 (2325 5675);
PAINT WHITE (2325 5675);
FORCENOTE
DC & AC=+/-80MV
(2325 5900) 0;
DISPLAY LEFT (2325 5900);
DISPLAY 0.936170 (2325 5900);
PAINT WHITE (2325 5900);
FORCENOTE
DEFAULT POWER-ON VID=1.1V
(2325 6050) 0;
DISPLAY LEFT (2325 6050);
DISPLAY 0.936170 (2325 6050);
PAINT WHITE (2325 6050);
FORCENOTE
IRM REV1.09
(2325 5225) 0;
DISPLAY LEFT (2325 5225);
DISPLAY 0.936170 (2325 5225);
PAINT WHITE (2325 5225);
FORCENOTE
PMBUS ADDRESS AND CONFIG
(-5275 1700) 0;
DISPLAY LEFT (-5275 1700);
DISPLAY 1.170213 (-5275 1700);
PAINT WHITE (-5275 1700);
FORCENOTE
PU34 = TBD/RAA229620GNP#HA0
(2250 4450) 0;
DISPLAY LEFT (2250 4450);
DISPLAY 1.021277 (2250 4450);
PAINT WHITE (2250 4450);
FORCENOTE
MAIN SOURCE:RENESAS BOM
(2250 4525) 0;
DISPLAY LEFT (2250 4525);
DISPLAY 1.276596 (2250 4525);
PAINT WHITE (2250 4525);
FORCENOTE
BOM NOTE
(2250 4650) 0;
DISPLAY LEFT (2250 4650);
DISPLAY 1.595745 (2250 4650);
PAINT WHITE (2250 4650);
QUIT
